FILE_TYPE = MACRO_DRAWING;
SET COLOR_WIRE YELLOW;
SET COLOR_PROP ORANGE;
SET COLOR_DOT WHITE;
SET COLOR_ARC YELLOW;
SET COLOR_BODY GREEN;
SET COLOR_NOTE PURPLE;
SET PROP_DISPLAY VALUE;
SET PAGE_NUMBER P14;
FORCEADD OFFPAGE_OUT..1
R 4
(-4550 10750);
FORCEPROP 2 LAST $XR0 26J9> 
J 0
(-4733 10750);
DISPLAY 0.638298 (-4733 10750);
PAINT MONO (-4733 10750);
FORCEPROP 1 LAST BODY_TYPE COMMENT
R 2
J 0
(-4560 10615);
DISPLAY 0.808511 (-4560 10615);
PAINT GREEN (-4560 10615);
DISPLAY INVISIBLE (-4560 10615);
FORCEPROP 1 LAST CDS_LMAN_SYM_OUTLINE -50,50,50,-50
R 2
J 0
(-4550 10750);
DISPLAY 0.468085 (-4550 10750);
PAINT GREEN (-4550 10750);
DISPLAY INVISIBLE (-4550 10750);
FORCEPROP 2 LAST CDS_LIB cls
J 0
(-4550 10750);
DISPLAY INVISIBLE (-4550 10750);
FORCEPROP 1 LAST OFFPAGE TRUE
R 2
J 0
(-4560 10695);
DISPLAY 0.808511 (-4560 10695);
PAINT GREEN (-4560 10695);
DISPLAY INVISIBLE (-4560 10695);
FORCEPROP 2 LAST PATH I104
J 0
(-4500 10850);
DISPLAY 1.021277 (-4500 10850);
DISPLAY INVISIBLE (-4500 10850);
FORCEADD RESISTOR..1
(-2800 10750);
FORCEPROP 1 LAST $LOCATION R385
J 2
(-3000 10750);
DISPLAY 1.212766 (-3000 10750);
PAINT GREEN (-3000 10750);
FORCEPROP 0 LAST CDS_LOCATION R385
J 0
(-2650 10900);
DISPLAY 1.021277 (-2650 10900);
DISPLAY INVISIBLE (-2650 10900);
FORCEPROP 0 LAST $SEC 1
J 0
(-2650 10900);
DISPLAY 0.680851 (-2650 10900);
PAINT MONO (-2650 10900);
DISPLAY INVISIBLE (-2650 10900);
FORCEPROP 0 LAST CDS_SEC 1
J 0
(-2650 10900);
DISPLAY 1.021277 (-2650 10900);
DISPLAY INVISIBLE (-2650 10900);
FORCEPROP 0 LASTPIN (-2900 10750) $PN 1
J 2
(-2910 10760);
DISPLAY 0.680851 (-2910 10760);
PAINT MONO (-2910 10760);
FORCEPROP 0 LASTPIN (-2650 10750) $PN 2
J 0
(-2640 10760);
DISPLAY 0.680851 (-2640 10760);
PAINT MONO (-2640 10760);
FORCEPROP 0 LAST PACKAGE 0402
J 0
(-2850 10800);
DISPLAY 1.021277 (-2850 10800);
FORCEPROP 1 LAST VALUE 33OHM
J 0
(-2550 10750);
DISPLAY 1.212766 (-2550 10750);
PAINT GREEN (-2550 10750);
FORCEPROP 1 LAST PATH I107
J 0
(-2997 10855);
DISPLAY 1.212766 (-2997 10855);
PAINT GREEN (-2997 10855);
DISPLAY INVISIBLE (-2997 10855);
FORCEPROP 1 LAST TOLERANCE 1%
J 0
(-2997 11005);
DISPLAY 1.212766 (-2997 11005);
PAINT GREEN (-2997 11005);
DISPLAY INVISIBLE (-2997 11005);
FORCEPROP 2 LAST CDS_LIB passive
J 0
(-2800 10750);
DISPLAY INVISIBLE (-2800 10750);
FORCEPROP 1 LAST CDS_LMAN_SYM_OUTLINE -50,50,100,-50
J 0
(-2800 10750);
DISPLAY 0.468085 (-2800 10750);
PAINT GREEN (-2800 10750);
DISPLAY INVISIBLE (-2800 10750);
FORCEPROP 1 LAST CLS_PN G155-133R0-01
J 0
(-2936 10950);
DISPLAY 1.212766 (-2936 10950);
PAINT GREEN (-2936 10950);
DISPLAY INVISIBLE (-2936 10950);
FORCEADD RESISTOR..1
(-2800 11350);
FORCEPROP 1 LAST $LOCATION R386
J 2
(-3000 11350);
DISPLAY 1.212766 (-3000 11350);
PAINT GREEN (-3000 11350);
FORCEPROP 0 LAST CDS_LOCATION R386
J 0
(-2650 11500);
DISPLAY 1.021277 (-2650 11500);
DISPLAY INVISIBLE (-2650 11500);
FORCEPROP 0 LAST $SEC 1
J 0
(-2650 11500);
DISPLAY 0.680851 (-2650 11500);
PAINT MONO (-2650 11500);
DISPLAY INVISIBLE (-2650 11500);
FORCEPROP 0 LAST CDS_SEC 1
J 0
(-2650 11500);
DISPLAY 1.021277 (-2650 11500);
DISPLAY INVISIBLE (-2650 11500);
FORCEPROP 0 LASTPIN (-2900 11350) $PN 1
J 2
(-2910 11360);
DISPLAY 0.680851 (-2910 11360);
PAINT MONO (-2910 11360);
FORCEPROP 0 LASTPIN (-2650 11350) $PN 2
J 0
(-2640 11360);
DISPLAY 0.680851 (-2640 11360);
PAINT MONO (-2640 11360);
FORCEPROP 0 LAST PACKAGE 0402
J 0
(-2850 11400);
DISPLAY 1.021277 (-2850 11400);
FORCEPROP 1 LAST VALUE 33OHM
J 0
(-2550 11350);
DISPLAY 1.212766 (-2550 11350);
PAINT GREEN (-2550 11350);
FORCEPROP 1 LAST CLS_PN G155-133R0-01
J 0
(-2936 11550);
DISPLAY 1.212766 (-2936 11550);
PAINT GREEN (-2936 11550);
DISPLAY INVISIBLE (-2936 11550);
FORCEPROP 1 LAST CDS_LMAN_SYM_OUTLINE -50,50,100,-50
J 0
(-2800 11350);
DISPLAY 0.468085 (-2800 11350);
PAINT GREEN (-2800 11350);
DISPLAY INVISIBLE (-2800 11350);
FORCEPROP 2 LAST CDS_LIB passive
J 0
(-2800 11350);
DISPLAY INVISIBLE (-2800 11350);
FORCEPROP 1 LAST TOLERANCE 1%
J 0
(-2997 11605);
DISPLAY 1.212766 (-2997 11605);
PAINT GREEN (-2997 11605);
DISPLAY INVISIBLE (-2997 11605);
FORCEPROP 1 LAST PATH I108
J 0
(-2997 11455);
DISPLAY 1.212766 (-2997 11455);
PAINT GREEN (-2997 11455);
DISPLAY INVISIBLE (-2997 11455);
FORCEADD OPTICAL..1
R 2
(-10500 12050);
FORCEPROP 1 LAST $LOCATION DS2
J 0
(-10312 12100);
DISPLAY 1.212766 (-10312 12100);
PAINT GREEN (-10312 12100);
FORCEPROP 0 LAST CDS_LOCATION DS2
J 0
(-10300 12200);
DISPLAY 1.021277 (-10300 12200);
DISPLAY INVISIBLE (-10300 12200);
FORCEPROP 0 LAST $SEC 1
J 0
(-10300 12200);
DISPLAY 0.680851 (-10300 12200);
PAINT MONO (-10300 12200);
DISPLAY INVISIBLE (-10300 12200);
FORCEPROP 0 LAST CDS_SEC 1
J 0
(-10300 12200);
DISPLAY 1.021277 (-10300 12200);
DISPLAY INVISIBLE (-10300 12200);
FORCEPROP 0 LASTPIN (-10250 12050) $PN A
J 0
(-10240 12060);
DISPLAY 0.680851 (-10240 12060);
PAINT MONO (-10240 12060);
FORCEPROP 0 LASTPIN (-10750 12050) $PN C
J 2
(-10760 12060);
DISPLAY 0.680851 (-10760 12060);
PAINT MONO (-10760 12060);
FORCEPROP 1 LAST CLS_PN G170-10143-01
J 2
(-10700 12100);
DISPLAY 1.212766 (-10700 12100);
PAINT GREEN (-10700 12100);
FORCEPROP 0 LAST PART_NUMBER LTST-C190KGKT
J 0
(-11450 12200);
DISPLAY 1.021277 (-11450 12200);
FORCEPROP 2 LASTPIN (-10250 12050) SIG_NAME UN$14$OPTICAL$I11$A
J 0
(-10240 12060);
DISPLAY 0.659574 (-10240 12060);
PAINT MONO (-10240 12060);
DISPLAY INVISIBLE (-10240 12060);
FORCEPROP 1 LAST CDS_LMAN_SYM_OUTLINE -150,100,150,-50
J 2
(-10500 12050);
DISPLAY 0.468085 (-10500 12050);
PAINT GREEN (-10500 12050);
DISPLAY INVISIBLE (-10500 12050);
FORCEPROP 2 LAST CDS_LIB discrete
J 0
(-10500 12050);
DISPLAY INVISIBLE (-10500 12050);
FORCEPROP 1 LAST PATH I11
J 2
(-10600 12250);
DISPLAY 1.212766 (-10600 12250);
PAINT GREEN (-10600 12250);
DISPLAY INVISIBLE (-10600 12250);
FORCEADD RESISTOR..1
(-2800 11050);
FORCEPROP 1 LAST $LOCATION R387
J 2
(-3000 11050);
DISPLAY 1.212766 (-3000 11050);
PAINT GREEN (-3000 11050);
FORCEPROP 0 LAST CDS_LOCATION R387
J 0
(-2650 11200);
DISPLAY 1.021277 (-2650 11200);
DISPLAY INVISIBLE (-2650 11200);
FORCEPROP 0 LAST $SEC 1
J 0
(-2650 11200);
DISPLAY 0.680851 (-2650 11200);
PAINT MONO (-2650 11200);
DISPLAY INVISIBLE (-2650 11200);
FORCEPROP 0 LAST CDS_SEC 1
J 0
(-2650 11200);
DISPLAY 1.021277 (-2650 11200);
DISPLAY INVISIBLE (-2650 11200);
FORCEPROP 0 LASTPIN (-2900 11050) $PN 1
J 2
(-2910 11060);
DISPLAY 0.680851 (-2910 11060);
PAINT MONO (-2910 11060);
FORCEPROP 0 LASTPIN (-2650 11050) $PN 2
J 0
(-2640 11060);
DISPLAY 0.680851 (-2640 11060);
PAINT MONO (-2640 11060);
FORCEPROP 0 LAST PACKAGE 0402
J 0
(-2850 11100);
DISPLAY 1.021277 (-2850 11100);
FORCEPROP 1 LAST VALUE 33OHM
J 0
(-2550 11050);
DISPLAY 1.212766 (-2550 11050);
PAINT GREEN (-2550 11050);
FORCEPROP 1 LAST PATH I110
J 0
(-2997 11155);
DISPLAY 1.212766 (-2997 11155);
PAINT GREEN (-2997 11155);
DISPLAY INVISIBLE (-2997 11155);
FORCEPROP 1 LAST TOLERANCE 1%
J 0
(-2997 11305);
DISPLAY 1.212766 (-2997 11305);
PAINT GREEN (-2997 11305);
DISPLAY INVISIBLE (-2997 11305);
FORCEPROP 1 LAST CDS_LMAN_SYM_OUTLINE -50,50,100,-50
J 0
(-2800 11050);
DISPLAY 0.468085 (-2800 11050);
PAINT GREEN (-2800 11050);
DISPLAY INVISIBLE (-2800 11050);
FORCEPROP 2 LAST CDS_LIB passive
J 0
(-2800 11050);
DISPLAY INVISIBLE (-2800 11050);
FORCEPROP 1 LAST CLS_PN G155-133R0-01
J 0
(-2936 11250);
DISPLAY 1.212766 (-2936 11250);
PAINT GREEN (-2936 11250);
DISPLAY INVISIBLE (-2936 11250);
FORCEADD OFFPAGE_OUT..1
R 4
(-4550 9550);
FORCEPROP 2 LAST $XR0 26K9> 
J 0
(-4733 9550);
DISPLAY 0.638298 (-4733 9550);
PAINT MONO (-4733 9550);
FORCEPROP 1 LAST BODY_TYPE COMMENT
R 2
J 0
(-4560 9415);
DISPLAY 0.808511 (-4560 9415);
PAINT GREEN (-4560 9415);
DISPLAY INVISIBLE (-4560 9415);
FORCEPROP 1 LAST CDS_LMAN_SYM_OUTLINE -50,50,50,-50
R 2
J 0
(-4550 9550);
DISPLAY 0.468085 (-4550 9550);
PAINT GREEN (-4550 9550);
DISPLAY INVISIBLE (-4550 9550);
FORCEPROP 2 LAST CDS_LIB cls
J 0
(-4550 9550);
DISPLAY INVISIBLE (-4550 9550);
FORCEPROP 1 LAST OFFPAGE TRUE
R 2
J 0
(-4560 9495);
DISPLAY 0.808511 (-4560 9495);
PAINT GREEN (-4560 9495);
DISPLAY INVISIBLE (-4560 9495);
FORCEPROP 2 LAST PATH I119
J 0
(-4500 9650);
DISPLAY 1.021277 (-4500 9650);
DISPLAY INVISIBLE (-4500 9650);
FORCEADD OPTICAL..1
R 2
(-10500 12400);
FORCEPROP 1 LAST $LOCATION DS1
J 0
(-10312 12450);
DISPLAY 1.212766 (-10312 12450);
PAINT GREEN (-10312 12450);
FORCEPROP 0 LAST CDS_LOCATION DS1
J 0
(-10300 12550);
DISPLAY 1.021277 (-10300 12550);
DISPLAY INVISIBLE (-10300 12550);
FORCEPROP 0 LAST $SEC 1
J 0
(-10300 12550);
DISPLAY 0.680851 (-10300 12550);
PAINT MONO (-10300 12550);
DISPLAY INVISIBLE (-10300 12550);
FORCEPROP 0 LAST CDS_SEC 1
J 0
(-10300 12550);
DISPLAY 1.021277 (-10300 12550);
DISPLAY INVISIBLE (-10300 12550);
FORCEPROP 0 LASTPIN (-10250 12400) $PN A
J 0
(-10240 12410);
DISPLAY 0.680851 (-10240 12410);
PAINT MONO (-10240 12410);
FORCEPROP 0 LASTPIN (-10750 12400) $PN C
J 2
(-10760 12410);
DISPLAY 0.680851 (-10760 12410);
PAINT MONO (-10760 12410);
FORCEPROP 1 LAST CLS_PN G170-10143-01
J 2
(-10700 12450);
DISPLAY 1.212766 (-10700 12450);
PAINT GREEN (-10700 12450);
FORCEPROP 0 LAST PART_NUMBER LTST-C190KGKT
J 0
(-11450 12550);
DISPLAY 1.021277 (-11450 12550);
FORCEPROP 2 LAST CDS_LIB discrete
J 0
(-10500 12400);
DISPLAY INVISIBLE (-10500 12400);
FORCEPROP 1 LAST CDS_LMAN_SYM_OUTLINE -150,100,150,-50
J 2
(-10500 12400);
DISPLAY 0.468085 (-10500 12400);
PAINT GREEN (-10500 12400);
DISPLAY INVISIBLE (-10500 12400);
FORCEPROP 2 LASTPIN (-10250 12400) SIG_NAME UN$14$OPTICAL$I12$A
J 0
(-10240 12410);
DISPLAY 0.659574 (-10240 12410);
PAINT MONO (-10240 12410);
DISPLAY INVISIBLE (-10240 12410);
FORCEPROP 1 LAST PATH I12
J 2
(-10600 12600);
DISPLAY 1.212766 (-10600 12600);
PAINT GREEN (-10600 12600);
DISPLAY INVISIBLE (-10600 12600);
FORCEADD OFFPAGE_OUT..1
R 4
(-4550 9850);
FORCEPROP 2 LAST $XR0 26J9> 
J 0
(-4733 9850);
DISPLAY 0.638298 (-4733 9850);
PAINT MONO (-4733 9850);
FORCEPROP 1 LAST BODY_TYPE COMMENT
R 2
J 0
(-4560 9715);
DISPLAY 0.808511 (-4560 9715);
PAINT GREEN (-4560 9715);
DISPLAY INVISIBLE (-4560 9715);
FORCEPROP 1 LAST CDS_LMAN_SYM_OUTLINE -50,50,50,-50
R 2
J 0
(-4550 9850);
DISPLAY 0.468085 (-4550 9850);
PAINT GREEN (-4550 9850);
DISPLAY INVISIBLE (-4550 9850);
FORCEPROP 2 LAST CDS_LIB cls
J 0
(-4550 9850);
DISPLAY INVISIBLE (-4550 9850);
FORCEPROP 1 LAST OFFPAGE TRUE
R 2
J 0
(-4560 9795);
DISPLAY 0.808511 (-4560 9795);
PAINT GREEN (-4560 9795);
DISPLAY INVISIBLE (-4560 9795);
FORCEPROP 2 LAST PATH I120
J 0
(-4500 9950);
DISPLAY 1.021277 (-4500 9950);
DISPLAY INVISIBLE (-4500 9950);
FORCEADD OFFPAGE_OUT..1
R 4
(-4550 9250);
FORCEPROP 2 LAST $XR0 26K9> 
J 0
(-4733 9250);
DISPLAY 0.638298 (-4733 9250);
PAINT MONO (-4733 9250);
FORCEPROP 2 LAST CDS_LIB cls
J 0
(-4550 9250);
DISPLAY INVISIBLE (-4550 9250);
FORCEPROP 1 LAST CDS_LMAN_SYM_OUTLINE -50,50,50,-50
R 2
J 0
(-4550 9250);
DISPLAY 0.468085 (-4550 9250);
PAINT GREEN (-4550 9250);
DISPLAY INVISIBLE (-4550 9250);
FORCEPROP 1 LAST BODY_TYPE COMMENT
R 2
J 0
(-4560 9115);
DISPLAY 0.808511 (-4560 9115);
PAINT GREEN (-4560 9115);
DISPLAY INVISIBLE (-4560 9115);
FORCEPROP 1 LAST OFFPAGE TRUE
R 2
J 0
(-4560 9195);
DISPLAY 0.808511 (-4560 9195);
PAINT GREEN (-4560 9195);
DISPLAY INVISIBLE (-4560 9195);
FORCEPROP 2 LAST PATH I121
J 0
(-4500 9350);
DISPLAY 1.021277 (-4500 9350);
DISPLAY INVISIBLE (-4500 9350);
FORCEADD OFFPAGE_OUT..1
R 4
(-4550 8000);
FORCEPROP 2 LAST $XR0 26K9> 
J 0
(-4733 8000);
DISPLAY 0.638298 (-4733 8000);
PAINT MONO (-4733 8000);
FORCEPROP 1 LAST BODY_TYPE COMMENT
R 2
J 0
(-4560 7865);
DISPLAY 0.808511 (-4560 7865);
PAINT GREEN (-4560 7865);
DISPLAY INVISIBLE (-4560 7865);
FORCEPROP 1 LAST CDS_LMAN_SYM_OUTLINE -50,50,50,-50
R 2
J 0
(-4550 8000);
DISPLAY 0.468085 (-4550 8000);
PAINT GREEN (-4550 8000);
DISPLAY INVISIBLE (-4550 8000);
FORCEPROP 2 LAST CDS_LIB cls
J 0
(-4550 8000);
DISPLAY INVISIBLE (-4550 8000);
FORCEPROP 1 LAST OFFPAGE TRUE
R 2
J 0
(-4560 7945);
DISPLAY 0.808511 (-4560 7945);
PAINT GREEN (-4560 7945);
DISPLAY INVISIBLE (-4560 7945);
FORCEPROP 2 LAST PATH I122
J 0
(-4500 8100);
DISPLAY 1.021277 (-4500 8100);
DISPLAY INVISIBLE (-4500 8100);
FORCEADD OFFPAGE_OUT..1
R 4
(-4550 8300);
FORCEPROP 2 LAST $XR0 26K9> 
J 0
(-4733 8300);
DISPLAY 0.638298 (-4733 8300);
PAINT MONO (-4733 8300);
FORCEPROP 1 LAST BODY_TYPE COMMENT
R 2
J 0
(-4560 8165);
DISPLAY 0.808511 (-4560 8165);
PAINT GREEN (-4560 8165);
DISPLAY INVISIBLE (-4560 8165);
FORCEPROP 1 LAST CDS_LMAN_SYM_OUTLINE -50,50,50,-50
R 2
J 0
(-4550 8300);
DISPLAY 0.468085 (-4550 8300);
PAINT GREEN (-4550 8300);
DISPLAY INVISIBLE (-4550 8300);
FORCEPROP 2 LAST CDS_LIB cls
J 0
(-4550 8300);
DISPLAY INVISIBLE (-4550 8300);
FORCEPROP 1 LAST OFFPAGE TRUE
R 2
J 0
(-4560 8245);
DISPLAY 0.808511 (-4560 8245);
PAINT GREEN (-4560 8245);
DISPLAY INVISIBLE (-4560 8245);
FORCEPROP 2 LAST PATH I123
J 0
(-4500 8400);
DISPLAY 1.021277 (-4500 8400);
DISPLAY INVISIBLE (-4500 8400);
FORCEADD OFFPAGE_OUT..1
R 4
(-4550 7700);
FORCEPROP 2 LAST $XR0 26K9> 
J 0
(-4733 7700);
DISPLAY 0.638298 (-4733 7700);
PAINT MONO (-4733 7700);
FORCEPROP 2 LAST CDS_LIB cls
J 0
(-4550 7700);
DISPLAY INVISIBLE (-4550 7700);
FORCEPROP 1 LAST CDS_LMAN_SYM_OUTLINE -50,50,50,-50
R 2
J 0
(-4550 7700);
DISPLAY 0.468085 (-4550 7700);
PAINT GREEN (-4550 7700);
DISPLAY INVISIBLE (-4550 7700);
FORCEPROP 1 LAST BODY_TYPE COMMENT
R 2
J 0
(-4560 7565);
DISPLAY 0.808511 (-4560 7565);
PAINT GREEN (-4560 7565);
DISPLAY INVISIBLE (-4560 7565);
FORCEPROP 1 LAST OFFPAGE TRUE
R 2
J 0
(-4560 7645);
DISPLAY 0.808511 (-4560 7645);
PAINT GREEN (-4560 7645);
DISPLAY INVISIBLE (-4560 7645);
FORCEPROP 2 LAST PATH I124
J 0
(-4500 7800);
DISPLAY 1.021277 (-4500 7800);
DISPLAY INVISIBLE (-4500 7800);
FORCEADD OFFPAGE_OUT..1
R 4
(-4550 6450);
FORCEPROP 2 LAST $XR0 26K9> 
J 0
(-4733 6450);
DISPLAY 0.638298 (-4733 6450);
PAINT MONO (-4733 6450);
FORCEPROP 1 LAST BODY_TYPE COMMENT
R 2
J 0
(-4560 6315);
DISPLAY 0.808511 (-4560 6315);
PAINT GREEN (-4560 6315);
DISPLAY INVISIBLE (-4560 6315);
FORCEPROP 1 LAST CDS_LMAN_SYM_OUTLINE -50,50,50,-50
R 2
J 0
(-4550 6450);
DISPLAY 0.468085 (-4550 6450);
PAINT GREEN (-4550 6450);
DISPLAY INVISIBLE (-4550 6450);
FORCEPROP 2 LAST CDS_LIB cls
J 0
(-4550 6450);
DISPLAY INVISIBLE (-4550 6450);
FORCEPROP 1 LAST OFFPAGE TRUE
R 2
J 0
(-4560 6395);
DISPLAY 0.808511 (-4560 6395);
PAINT GREEN (-4560 6395);
DISPLAY INVISIBLE (-4560 6395);
FORCEPROP 2 LAST PATH I125
J 0
(-4500 6550);
DISPLAY 1.021277 (-4500 6550);
DISPLAY INVISIBLE (-4500 6550);
FORCEADD OFFPAGE_OUT..1
R 4
(-4550 6750);
FORCEPROP 2 LAST $XR0 26K9> 
J 0
(-4733 6750);
DISPLAY 0.638298 (-4733 6750);
PAINT MONO (-4733 6750);
FORCEPROP 1 LAST BODY_TYPE COMMENT
R 2
J 0
(-4560 6615);
DISPLAY 0.808511 (-4560 6615);
PAINT GREEN (-4560 6615);
DISPLAY INVISIBLE (-4560 6615);
FORCEPROP 1 LAST CDS_LMAN_SYM_OUTLINE -50,50,50,-50
R 2
J 0
(-4550 6750);
DISPLAY 0.468085 (-4550 6750);
PAINT GREEN (-4550 6750);
DISPLAY INVISIBLE (-4550 6750);
FORCEPROP 2 LAST CDS_LIB cls
J 0
(-4550 6750);
DISPLAY INVISIBLE (-4550 6750);
FORCEPROP 1 LAST OFFPAGE TRUE
R 2
J 0
(-4560 6695);
DISPLAY 0.808511 (-4560 6695);
PAINT GREEN (-4560 6695);
DISPLAY INVISIBLE (-4560 6695);
FORCEPROP 2 LAST PATH I126
J 0
(-4500 6850);
DISPLAY 1.021277 (-4500 6850);
DISPLAY INVISIBLE (-4500 6850);
FORCEADD OFFPAGE_OUT..1
R 4
(-4550 6150);
FORCEPROP 2 LAST $XR0 26K9> 
J 0
(-4733 6150);
DISPLAY 0.638298 (-4733 6150);
PAINT MONO (-4733 6150);
FORCEPROP 2 LAST CDS_LIB cls
J 0
(-4550 6150);
DISPLAY INVISIBLE (-4550 6150);
FORCEPROP 1 LAST CDS_LMAN_SYM_OUTLINE -50,50,50,-50
R 2
J 0
(-4550 6150);
DISPLAY 0.468085 (-4550 6150);
PAINT GREEN (-4550 6150);
DISPLAY INVISIBLE (-4550 6150);
FORCEPROP 1 LAST BODY_TYPE COMMENT
R 2
J 0
(-4560 6015);
DISPLAY 0.808511 (-4560 6015);
PAINT GREEN (-4560 6015);
DISPLAY INVISIBLE (-4560 6015);
FORCEPROP 1 LAST OFFPAGE TRUE
R 2
J 0
(-4560 6095);
DISPLAY 0.808511 (-4560 6095);
PAINT GREEN (-4560 6095);
DISPLAY INVISIBLE (-4560 6095);
FORCEPROP 2 LAST PATH I127
J 0
(-4500 6250);
DISPLAY 1.021277 (-4500 6250);
DISPLAY INVISIBLE (-4500 6250);
FORCEADD VCC..1
(-500 12050);
FORCEPROP 3 LASTPIN (-450 12000) SIG_NAME XP3R3V_FPGA\g
J 0
(-440 12010);
DISPLAY 0.659574 (-440 12010);
PAINT MONO (-440 12010);
DISPLAY INVISIBLE (-440 12010);
FORCEPROP 0 LAST VOLTAGE 3.3V
J 0
(-750 12200);
DISPLAY 1.021277 (-750 12200);
DISPLAY BOTH (-750 12200);
FORCEPROP 1 LAST HDL_POWER XP3R3V_FPGA
J 1
(-445 12105);
DISPLAY 1.021277 (-445 12105);
PAINT GREEN (-445 12105);
FORCEPROP 1 LAST CDS_LMAN_SYM_OUTLINE -250,250,250,-250
J 0
(-500 12050);
DISPLAY 0.468085 (-500 12050);
PAINT GREEN (-500 12050);
DISPLAY INVISIBLE (-500 12050);
FORCEPROP 2 LAST CDS_LIB cls
J 0
(-500 12050);
DISPLAY INVISIBLE (-500 12050);
FORCEPROP 1 LAST BODY_TYPE PLUMBING
J 0
(-545 12007);
DISPLAY 0.340426 (-545 12007);
PAINT GREEN (-545 12007);
DISPLAY INVISIBLE (-545 12007);
FORCEPROP 1 LAST PATH I128
J 0
(-465 12140);
DISPLAY 0.808511 (-465 12140);
PAINT GREEN (-465 12140);
DISPLAY INVISIBLE (-465 12140);
FORCEADD OFFPAGE_OUT..1
R 4
(-4500 4600);
FORCEPROP 2 LAST $XR0 26L9> 
J 0
(-4683 4600);
DISPLAY 0.638298 (-4683 4600);
PAINT MONO (-4683 4600);
FORCEPROP 2 LAST CDS_LIB cls
J 0
(-4500 4600);
DISPLAY INVISIBLE (-4500 4600);
FORCEPROP 1 LAST CDS_LMAN_SYM_OUTLINE -50,50,50,-50
R 2
J 0
(-4500 4600);
DISPLAY 0.468085 (-4500 4600);
PAINT GREEN (-4500 4600);
DISPLAY INVISIBLE (-4500 4600);
FORCEPROP 1 LAST BODY_TYPE COMMENT
R 2
J 0
(-4510 4465);
DISPLAY 0.808511 (-4510 4465);
PAINT GREEN (-4510 4465);
DISPLAY INVISIBLE (-4510 4465);
FORCEPROP 1 LAST OFFPAGE TRUE
R 2
J 0
(-4510 4545);
DISPLAY 0.808511 (-4510 4545);
PAINT GREEN (-4510 4545);
DISPLAY INVISIBLE (-4510 4545);
FORCEPROP 2 LAST PATH I133
J 0
(-4450 4700);
DISPLAY 1.021277 (-4450 4700);
DISPLAY INVISIBLE (-4450 4700);
FORCEADD OFFPAGE_OUT..1
R 4
(-4500 5200);
FORCEPROP 2 LAST $XR0 26K9> 
J 0
(-4683 5200);
DISPLAY 0.638298 (-4683 5200);
PAINT MONO (-4683 5200);
FORCEPROP 1 LAST BODY_TYPE COMMENT
R 2
J 0
(-4510 5065);
DISPLAY 0.808511 (-4510 5065);
PAINT GREEN (-4510 5065);
DISPLAY INVISIBLE (-4510 5065);
FORCEPROP 1 LAST CDS_LMAN_SYM_OUTLINE -50,50,50,-50
R 2
J 0
(-4500 5200);
DISPLAY 0.468085 (-4500 5200);
PAINT GREEN (-4500 5200);
DISPLAY INVISIBLE (-4500 5200);
FORCEPROP 2 LAST CDS_LIB cls
J 0
(-4500 5200);
DISPLAY INVISIBLE (-4500 5200);
FORCEPROP 1 LAST OFFPAGE TRUE
R 2
J 0
(-4510 5145);
DISPLAY 0.808511 (-4510 5145);
PAINT GREEN (-4510 5145);
DISPLAY INVISIBLE (-4510 5145);
FORCEPROP 2 LAST PATH I134
J 0
(-4450 5300);
DISPLAY 1.021277 (-4450 5300);
DISPLAY INVISIBLE (-4450 5300);
FORCEADD OFFPAGE_OUT..1
R 4
(-4500 4900);
FORCEPROP 2 LAST $XR0 26K9> 
J 0
(-4683 4900);
DISPLAY 0.638298 (-4683 4900);
PAINT MONO (-4683 4900);
FORCEPROP 1 LAST BODY_TYPE COMMENT
R 2
J 0
(-4510 4765);
DISPLAY 0.808511 (-4510 4765);
PAINT GREEN (-4510 4765);
DISPLAY INVISIBLE (-4510 4765);
FORCEPROP 1 LAST CDS_LMAN_SYM_OUTLINE -50,50,50,-50
R 2
J 0
(-4500 4900);
DISPLAY 0.468085 (-4500 4900);
PAINT GREEN (-4500 4900);
DISPLAY INVISIBLE (-4500 4900);
FORCEPROP 2 LAST CDS_LIB cls
J 0
(-4500 4900);
DISPLAY INVISIBLE (-4500 4900);
FORCEPROP 1 LAST OFFPAGE TRUE
R 2
J 0
(-4510 4845);
DISPLAY 0.808511 (-4510 4845);
PAINT GREEN (-4510 4845);
DISPLAY INVISIBLE (-4510 4845);
FORCEPROP 2 LAST PATH I135
J 0
(-4450 5000);
DISPLAY 1.021277 (-4450 5000);
DISPLAY INVISIBLE (-4450 5000);
FORCEADD OPTICAL..1
R 2
(-10500 11700);
FORCEPROP 1 LAST LOCATION DS3
J 0
(-10312 11750);
DISPLAY 1.212766 (-10312 11750);
PAINT GREEN (-10312 11750);
FORCEPROP 0 LAST $SEC 1
J 0
(-10300 11850);
DISPLAY 0.680851 (-10300 11850);
PAINT MONO (-10300 11850);
DISPLAY INVISIBLE (-10300 11850);
FORCEPROP 0 LAST CDS_SEC 1
J 0
(-10300 11850);
DISPLAY 1.021277 (-10300 11850);
DISPLAY INVISIBLE (-10300 11850);
FORCEPROP 0 LASTPIN (-10250 11700) $PN A
J 0
(-10240 11710);
DISPLAY 0.680851 (-10240 11710);
PAINT MONO (-10240 11710);
FORCEPROP 0 LASTPIN (-10750 11700) $PN C
J 2
(-10760 11710);
DISPLAY 0.680851 (-10760 11710);
PAINT MONO (-10760 11710);
FORCEPROP 1 LAST CLS_PN G170-10143-01
J 2
(-10700 11750);
DISPLAY 1.212766 (-10700 11750);
PAINT GREEN (-10700 11750);
FORCEPROP 0 LAST PART_NUMBER LTST-C190KGKT
J 0
(-11450 11850);
DISPLAY 1.021277 (-11450 11850);
FORCEPROP 1 LAST CDS_LMAN_SYM_OUTLINE -150,100,150,-50
J 2
(-10500 11700);
DISPLAY 0.468085 (-10500 11700);
PAINT GREEN (-10500 11700);
DISPLAY INVISIBLE (-10500 11700);
FORCEPROP 2 LAST CDS_LIB discrete
J 0
(-10500 11700);
DISPLAY INVISIBLE (-10500 11700);
FORCEPROP 2 LASTPIN (-10250 11700) SIG_NAME UN$14$OPTICAL$I136$A
J 0
(-10240 11710);
DISPLAY 0.659574 (-10240 11710);
PAINT MONO (-10240 11710);
DISPLAY INVISIBLE (-10240 11710);
FORCEPROP 1 LAST PATH I136
J 2
(-10600 11900);
DISPLAY 1.212766 (-10600 11900);
PAINT GREEN (-10600 11900);
DISPLAY INVISIBLE (-10600 11900);
FORCEADD OPTICAL..1
R 2
(-10500 11350);
FORCEPROP 1 LAST LOCATION DS4
J 0
(-10312 11400);
DISPLAY 1.212766 (-10312 11400);
PAINT GREEN (-10312 11400);
FORCEPROP 0 LAST $SEC 1
J 0
(-10300 11500);
DISPLAY 0.680851 (-10300 11500);
PAINT MONO (-10300 11500);
DISPLAY INVISIBLE (-10300 11500);
FORCEPROP 0 LAST CDS_SEC 1
J 0
(-10300 11500);
DISPLAY 1.021277 (-10300 11500);
DISPLAY INVISIBLE (-10300 11500);
FORCEPROP 0 LASTPIN (-10250 11350) $PN A
J 0
(-10240 11360);
DISPLAY 0.680851 (-10240 11360);
PAINT MONO (-10240 11360);
FORCEPROP 0 LASTPIN (-10750 11350) $PN C
J 2
(-10760 11360);
DISPLAY 0.680851 (-10760 11360);
PAINT MONO (-10760 11360);
FORCEPROP 0 LAST PART_NUMBER LTST-C190KGKT
J 0
(-11450 11500);
DISPLAY 1.021277 (-11450 11500);
FORCEPROP 1 LAST CLS_PN G170-10143-01
J 2
(-10700 11400);
DISPLAY 1.212766 (-10700 11400);
PAINT GREEN (-10700 11400);
FORCEPROP 1 LAST CDS_LMAN_SYM_OUTLINE -150,100,150,-50
J 2
(-10500 11350);
DISPLAY 0.468085 (-10500 11350);
PAINT GREEN (-10500 11350);
DISPLAY INVISIBLE (-10500 11350);
FORCEPROP 2 LAST CDS_LIB discrete
J 0
(-10500 11350);
DISPLAY INVISIBLE (-10500 11350);
FORCEPROP 2 LASTPIN (-10250 11350) SIG_NAME UN$14$OPTICAL$I137$A
J 0
(-10240 11360);
DISPLAY 0.659574 (-10240 11360);
PAINT MONO (-10240 11360);
DISPLAY INVISIBLE (-10240 11360);
FORCEPROP 1 LAST PATH I137
J 2
(-10600 11550);
DISPLAY 1.212766 (-10600 11550);
PAINT GREEN (-10600 11550);
DISPLAY INVISIBLE (-10600 11550);
FORCEADD OPTICAL..1
R 2
(-10500 10950);
FORCEPROP 1 LAST LOCATION DS10
J 0
(-10312 11000);
DISPLAY 1.212766 (-10312 11000);
PAINT GREEN (-10312 11000);
FORCEPROP 0 LAST $SEC 1
J 0
(-10300 11100);
DISPLAY 0.680851 (-10300 11100);
PAINT MONO (-10300 11100);
DISPLAY INVISIBLE (-10300 11100);
FORCEPROP 0 LAST CDS_SEC 1
J 0
(-10300 11100);
DISPLAY 1.021277 (-10300 11100);
DISPLAY INVISIBLE (-10300 11100);
FORCEPROP 0 LASTPIN (-10250 10950) $PN A
J 0
(-10240 10960);
DISPLAY 0.680851 (-10240 10960);
PAINT MONO (-10240 10960);
FORCEPROP 0 LASTPIN (-10750 10950) $PN C
J 2
(-10760 10960);
DISPLAY 0.680851 (-10760 10960);
PAINT MONO (-10760 10960);
FORCEPROP 0 LAST PART_NUMBER LTST-C190KGKT
J 0
(-11450 11100);
DISPLAY 1.021277 (-11450 11100);
FORCEPROP 1 LAST CLS_PN G170-10143-01
J 2
(-10700 11000);
DISPLAY 1.212766 (-10700 11000);
PAINT GREEN (-10700 11000);
FORCEPROP 1 LAST PATH I138
J 2
(-10600 11150);
DISPLAY 1.212766 (-10600 11150);
PAINT GREEN (-10600 11150);
DISPLAY INVISIBLE (-10600 11150);
FORCEPROP 2 LASTPIN (-10250 10950) SIG_NAME UN$14$OPTICAL$I138$A
J 0
(-10240 10960);
DISPLAY 0.659574 (-10240 10960);
PAINT MONO (-10240 10960);
DISPLAY INVISIBLE (-10240 10960);
FORCEPROP 2 LAST CDS_LIB discrete
J 0
(-10500 10950);
DISPLAY INVISIBLE (-10500 10950);
FORCEPROP 1 LAST CDS_LMAN_SYM_OUTLINE -150,100,150,-50
J 2
(-10500 10950);
DISPLAY 0.468085 (-10500 10950);
PAINT GREEN (-10500 10950);
DISPLAY INVISIBLE (-10500 10950);
FORCEADD OPTICAL..1
R 2
(-10500 10650);
FORCEPROP 1 LAST LOCATION DS11
J 0
(-10312 10700);
DISPLAY 1.212766 (-10312 10700);
PAINT GREEN (-10312 10700);
FORCEPROP 0 LAST $SEC 1
J 0
(-10300 10800);
DISPLAY 0.680851 (-10300 10800);
PAINT MONO (-10300 10800);
DISPLAY INVISIBLE (-10300 10800);
FORCEPROP 0 LAST CDS_SEC 1
J 0
(-10300 10800);
DISPLAY 1.021277 (-10300 10800);
DISPLAY INVISIBLE (-10300 10800);
FORCEPROP 0 LASTPIN (-10250 10650) $PN A
J 0
(-10240 10660);
DISPLAY 0.680851 (-10240 10660);
PAINT MONO (-10240 10660);
FORCEPROP 0 LASTPIN (-10750 10650) $PN C
J 2
(-10760 10660);
DISPLAY 0.680851 (-10760 10660);
PAINT MONO (-10760 10660);
FORCEPROP 0 LAST PART_NUMBER LTST-C190KGKT
J 0
(-11450 10800);
DISPLAY 1.021277 (-11450 10800);
FORCEPROP 1 LAST CLS_PN G170-10143-01
J 2
(-10700 10700);
DISPLAY 1.212766 (-10700 10700);
PAINT GREEN (-10700 10700);
FORCEPROP 1 LAST PATH I139
J 2
(-10600 10850);
DISPLAY 1.212766 (-10600 10850);
PAINT GREEN (-10600 10850);
DISPLAY INVISIBLE (-10600 10850);
FORCEPROP 2 LASTPIN (-10250 10650) SIG_NAME UN$14$OPTICAL$I139$A
J 0
(-10240 10660);
DISPLAY 0.659574 (-10240 10660);
PAINT MONO (-10240 10660);
DISPLAY INVISIBLE (-10240 10660);
FORCEPROP 2 LAST CDS_LIB discrete
J 0
(-10500 10650);
DISPLAY INVISIBLE (-10500 10650);
FORCEPROP 1 LAST CDS_LMAN_SYM_OUTLINE -150,100,150,-50
J 2
(-10500 10650);
DISPLAY 0.468085 (-10500 10650);
PAINT GREEN (-10500 10650);
DISPLAY INVISIBLE (-10500 10650);
FORCEADD OPTICAL..1
R 2
(-10600 9200);
FORCEPROP 1 LAST LOCATION DS6
J 0
(-10412 9250);
DISPLAY 1.212766 (-10412 9250);
PAINT GREEN (-10412 9250);
FORCEPROP 0 LAST $SEC 1
J 0
(-11550 9400);
DISPLAY 0.680851 (-11550 9400);
PAINT MONO (-11550 9400);
DISPLAY INVISIBLE (-11550 9400);
FORCEPROP 0 LAST CDS_SEC 1
J 0
(-11550 9400);
DISPLAY 1.021277 (-11550 9400);
DISPLAY INVISIBLE (-11550 9400);
FORCEPROP 0 LASTPIN (-10350 9200) $PN A
J 0
(-10340 9210);
DISPLAY 0.680851 (-10340 9210);
PAINT MONO (-10340 9210);
FORCEPROP 0 LASTPIN (-10850 9200) $PN C
J 2
(-10860 9210);
DISPLAY 0.680851 (-10860 9210);
PAINT MONO (-10860 9210);
FORCEPROP 0 LAST PART_NUMBER LTST-C190KGKT
J 0
(-11550 9350);
DISPLAY 1.021277 (-11550 9350);
FORCEPROP 1 LAST CLS_PN G170-10143-01
J 2
(-10800 9250);
DISPLAY 1.212766 (-10800 9250);
PAINT GREEN (-10800 9250);
FORCEPROP 1 LAST PATH I140
J 2
(-10700 9400);
DISPLAY 1.212766 (-10700 9400);
PAINT GREEN (-10700 9400);
DISPLAY INVISIBLE (-10700 9400);
FORCEPROP 2 LASTPIN (-10350 9200) SIG_NAME UN$14$OPTICAL$I140$A
J 0
(-10340 9210);
DISPLAY 0.659574 (-10340 9210);
PAINT MONO (-10340 9210);
DISPLAY INVISIBLE (-10340 9210);
FORCEPROP 2 LAST CDS_LIB discrete
J 0
(-10600 9200);
DISPLAY INVISIBLE (-10600 9200);
FORCEPROP 1 LAST CDS_LMAN_SYM_OUTLINE -150,100,150,-50
J 2
(-10600 9200);
DISPLAY 0.468085 (-10600 9200);
PAINT GREEN (-10600 9200);
DISPLAY INVISIBLE (-10600 9200);
FORCEADD OPTICAL..1
R 2
(-10600 8850);
FORCEPROP 1 LAST LOCATION DS7
J 0
(-10412 8900);
DISPLAY 1.212766 (-10412 8900);
PAINT GREEN (-10412 8900);
FORCEPROP 0 LAST $SEC 1
J 0
(-11550 9050);
DISPLAY 0.680851 (-11550 9050);
PAINT MONO (-11550 9050);
DISPLAY INVISIBLE (-11550 9050);
FORCEPROP 0 LAST CDS_SEC 1
J 0
(-11550 9050);
DISPLAY 1.021277 (-11550 9050);
DISPLAY INVISIBLE (-11550 9050);
FORCEPROP 0 LASTPIN (-10350 8850) $PN A
J 0
(-10340 8860);
DISPLAY 0.680851 (-10340 8860);
PAINT MONO (-10340 8860);
FORCEPROP 0 LASTPIN (-10850 8850) $PN C
J 2
(-10860 8860);
DISPLAY 0.680851 (-10860 8860);
PAINT MONO (-10860 8860);
FORCEPROP 1 LAST CLS_PN G170-10143-01
J 2
(-10800 8900);
DISPLAY 1.212766 (-10800 8900);
PAINT GREEN (-10800 8900);
FORCEPROP 0 LAST PART_NUMBER LTST-C190KGKT
J 0
(-11550 9000);
DISPLAY 1.021277 (-11550 9000);
FORCEPROP 1 LAST PATH I141
J 2
(-10700 9050);
DISPLAY 1.212766 (-10700 9050);
PAINT GREEN (-10700 9050);
DISPLAY INVISIBLE (-10700 9050);
FORCEPROP 2 LASTPIN (-10350 8850) SIG_NAME UN$14$OPTICAL$I141$A
J 0
(-10340 8860);
DISPLAY 0.659574 (-10340 8860);
PAINT MONO (-10340 8860);
DISPLAY INVISIBLE (-10340 8860);
FORCEPROP 2 LAST CDS_LIB discrete
J 0
(-10600 8850);
DISPLAY INVISIBLE (-10600 8850);
FORCEPROP 1 LAST CDS_LMAN_SYM_OUTLINE -150,100,150,-50
J 2
(-10600 8850);
DISPLAY 0.468085 (-10600 8850);
PAINT GREEN (-10600 8850);
DISPLAY INVISIBLE (-10600 8850);
FORCEADD OPTICAL..1
R 2
(-10600 8500);
FORCEPROP 1 LAST LOCATION DS8
J 0
(-10412 8550);
DISPLAY 1.212766 (-10412 8550);
PAINT GREEN (-10412 8550);
FORCEPROP 0 LAST $SEC 1
J 0
(-11550 8700);
DISPLAY 0.680851 (-11550 8700);
PAINT MONO (-11550 8700);
DISPLAY INVISIBLE (-11550 8700);
FORCEPROP 0 LAST CDS_SEC 1
J 0
(-11550 8700);
DISPLAY 1.021277 (-11550 8700);
DISPLAY INVISIBLE (-11550 8700);
FORCEPROP 0 LASTPIN (-10350 8500) $PN A
J 0
(-10340 8510);
DISPLAY 0.680851 (-10340 8510);
PAINT MONO (-10340 8510);
FORCEPROP 0 LASTPIN (-10850 8500) $PN C
J 2
(-10860 8510);
DISPLAY 0.680851 (-10860 8510);
PAINT MONO (-10860 8510);
FORCEPROP 0 LAST PART_NUMBER LTST-C190KGKT
J 0
(-11550 8650);
DISPLAY 1.021277 (-11550 8650);
FORCEPROP 1 LAST CLS_PN G170-10143-01
J 2
(-10800 8550);
DISPLAY 1.212766 (-10800 8550);
PAINT GREEN (-10800 8550);
FORCEPROP 1 LAST PATH I142
J 2
(-10700 8700);
DISPLAY 1.212766 (-10700 8700);
PAINT GREEN (-10700 8700);
DISPLAY INVISIBLE (-10700 8700);
FORCEPROP 2 LASTPIN (-10350 8500) SIG_NAME UN$14$OPTICAL$I142$A
J 0
(-10340 8510);
DISPLAY 0.659574 (-10340 8510);
PAINT MONO (-10340 8510);
DISPLAY INVISIBLE (-10340 8510);
FORCEPROP 2 LAST CDS_LIB discrete
J 0
(-10600 8500);
DISPLAY INVISIBLE (-10600 8500);
FORCEPROP 1 LAST CDS_LMAN_SYM_OUTLINE -150,100,150,-50
J 2
(-10600 8500);
DISPLAY 0.468085 (-10600 8500);
PAINT GREEN (-10600 8500);
DISPLAY INVISIBLE (-10600 8500);
FORCEADD OPTICAL..1
R 2
(-10600 8100);
FORCEPROP 1 LAST LOCATION DS5
J 0
(-10412 8150);
DISPLAY 1.212766 (-10412 8150);
PAINT GREEN (-10412 8150);
FORCEPROP 0 LAST $SEC 1
J 0
(-11550 8300);
DISPLAY 0.680851 (-11550 8300);
PAINT MONO (-11550 8300);
DISPLAY INVISIBLE (-11550 8300);
FORCEPROP 0 LAST CDS_SEC 1
J 0
(-11550 8300);
DISPLAY 1.021277 (-11550 8300);
DISPLAY INVISIBLE (-11550 8300);
FORCEPROP 0 LASTPIN (-10350 8100) $PN A
J 0
(-10340 8110);
DISPLAY 0.680851 (-10340 8110);
PAINT MONO (-10340 8110);
FORCEPROP 0 LASTPIN (-10850 8100) $PN C
J 2
(-10860 8110);
DISPLAY 0.680851 (-10860 8110);
PAINT MONO (-10860 8110);
FORCEPROP 0 LAST PART_NUMBER LTST-C190KGKT
J 0
(-11550 8250);
DISPLAY 1.021277 (-11550 8250);
FORCEPROP 1 LAST CLS_PN G170-10143-01
J 2
(-10800 8150);
DISPLAY 1.212766 (-10800 8150);
PAINT GREEN (-10800 8150);
FORCEPROP 1 LAST PATH I143
J 2
(-10700 8300);
DISPLAY 1.212766 (-10700 8300);
PAINT GREEN (-10700 8300);
DISPLAY INVISIBLE (-10700 8300);
FORCEPROP 2 LASTPIN (-10350 8100) SIG_NAME UN$14$OPTICAL$I143$A
J 0
(-10340 8110);
DISPLAY 0.659574 (-10340 8110);
PAINT MONO (-10340 8110);
DISPLAY INVISIBLE (-10340 8110);
FORCEPROP 2 LAST CDS_LIB discrete
J 0
(-10600 8100);
DISPLAY INVISIBLE (-10600 8100);
FORCEPROP 1 LAST CDS_LMAN_SYM_OUTLINE -150,100,150,-50
J 2
(-10600 8100);
DISPLAY 0.468085 (-10600 8100);
PAINT GREEN (-10600 8100);
DISPLAY INVISIBLE (-10600 8100);
FORCEADD RESISTOR..1
(-2800 9550);
FORCEPROP 1 LAST LOCATION R390
J 2
(-2950 9550);
DISPLAY 1.212766 (-2950 9550);
PAINT GREEN (-2950 9550);
FORCEPROP 0 LAST $SEC 1
J 0
(-2650 9700);
DISPLAY 0.680851 (-2650 9700);
PAINT MONO (-2650 9700);
DISPLAY INVISIBLE (-2650 9700);
FORCEPROP 0 LAST CDS_SEC 1
J 0
(-2650 9700);
DISPLAY 1.021277 (-2650 9700);
DISPLAY INVISIBLE (-2650 9700);
FORCEPROP 0 LASTPIN (-2900 9550) $PN 1
J 2
(-2910 9560);
DISPLAY 0.680851 (-2910 9560);
PAINT MONO (-2910 9560);
FORCEPROP 0 LASTPIN (-2650 9550) $PN 2
J 0
(-2640 9560);
DISPLAY 0.680851 (-2640 9560);
PAINT MONO (-2640 9560);
FORCEPROP 0 LAST PACKAGE 0402
J 0
(-2850 9600);
DISPLAY 1.021277 (-2850 9600);
FORCEPROP 1 LAST VALUE 33OHM
J 0
(-2550 9550);
DISPLAY 1.212766 (-2550 9550);
PAINT GREEN (-2550 9550);
FORCEPROP 1 LAST PATH I146
J 0
(-2997 9655);
DISPLAY 1.212766 (-2997 9655);
PAINT GREEN (-2997 9655);
DISPLAY INVISIBLE (-2997 9655);
FORCEPROP 1 LAST TOLERANCE 1%
J 0
(-2997 9805);
DISPLAY 1.212766 (-2997 9805);
PAINT GREEN (-2997 9805);
DISPLAY INVISIBLE (-2997 9805);
FORCEPROP 1 LAST CDS_LMAN_SYM_OUTLINE -50,50,100,-50
J 0
(-2800 9550);
DISPLAY 0.468085 (-2800 9550);
PAINT GREEN (-2800 9550);
DISPLAY INVISIBLE (-2800 9550);
FORCEPROP 2 LAST CDS_LIB passive
J 0
(-2800 9550);
DISPLAY INVISIBLE (-2800 9550);
FORCEPROP 1 LAST CLS_PN G155-133R0-01
J 0
(-2936 9750);
DISPLAY 1.212766 (-2936 9750);
PAINT GREEN (-2936 9750);
DISPLAY INVISIBLE (-2936 9750);
FORCEADD RESISTOR..1
(-2800 9250);
FORCEPROP 1 LAST LOCATION R388
J 2
(-2950 9250);
DISPLAY 1.212766 (-2950 9250);
PAINT GREEN (-2950 9250);
FORCEPROP 0 LAST $SEC 1
J 0
(-2650 9400);
DISPLAY 0.680851 (-2650 9400);
PAINT MONO (-2650 9400);
DISPLAY INVISIBLE (-2650 9400);
FORCEPROP 0 LAST CDS_SEC 1
J 0
(-2650 9400);
DISPLAY 1.021277 (-2650 9400);
DISPLAY INVISIBLE (-2650 9400);
FORCEPROP 0 LASTPIN (-2900 9250) $PN 1
J 2
(-2910 9260);
DISPLAY 0.680851 (-2910 9260);
PAINT MONO (-2910 9260);
FORCEPROP 0 LASTPIN (-2650 9250) $PN 2
J 0
(-2640 9260);
DISPLAY 0.680851 (-2640 9260);
PAINT MONO (-2640 9260);
FORCEPROP 1 LAST VALUE 33OHM
J 0
(-2550 9250);
DISPLAY 1.212766 (-2550 9250);
PAINT GREEN (-2550 9250);
FORCEPROP 0 LAST PACKAGE 0402
J 0
(-2850 9300);
DISPLAY 1.021277 (-2850 9300);
FORCEPROP 1 LAST CLS_PN G155-133R0-01
J 0
(-2936 9450);
DISPLAY 1.212766 (-2936 9450);
PAINT GREEN (-2936 9450);
DISPLAY INVISIBLE (-2936 9450);
FORCEPROP 2 LAST CDS_LIB passive
J 0
(-2800 9250);
DISPLAY INVISIBLE (-2800 9250);
FORCEPROP 1 LAST CDS_LMAN_SYM_OUTLINE -50,50,100,-50
J 0
(-2800 9250);
DISPLAY 0.468085 (-2800 9250);
PAINT GREEN (-2800 9250);
DISPLAY INVISIBLE (-2800 9250);
FORCEPROP 1 LAST TOLERANCE 1%
J 0
(-2997 9505);
DISPLAY 1.212766 (-2997 9505);
PAINT GREEN (-2997 9505);
DISPLAY INVISIBLE (-2997 9505);
FORCEPROP 1 LAST PATH I147
J 0
(-2997 9355);
DISPLAY 1.212766 (-2997 9355);
PAINT GREEN (-2997 9355);
DISPLAY INVISIBLE (-2997 9355);
FORCEADD RESISTOR..1
(-2800 9850);
FORCEPROP 1 LAST LOCATION R389
J 2
(-2950 9850);
DISPLAY 1.212766 (-2950 9850);
PAINT GREEN (-2950 9850);
FORCEPROP 0 LAST $SEC 1
J 0
(-2650 10000);
DISPLAY 0.680851 (-2650 10000);
PAINT MONO (-2650 10000);
DISPLAY INVISIBLE (-2650 10000);
FORCEPROP 0 LAST CDS_SEC 1
J 0
(-2650 10000);
DISPLAY 1.021277 (-2650 10000);
DISPLAY INVISIBLE (-2650 10000);
FORCEPROP 0 LASTPIN (-2900 9850) $PN 1
J 2
(-2910 9860);
DISPLAY 0.680851 (-2910 9860);
PAINT MONO (-2910 9860);
FORCEPROP 0 LASTPIN (-2650 9850) $PN 2
J 0
(-2640 9860);
DISPLAY 0.680851 (-2640 9860);
PAINT MONO (-2640 9860);
FORCEPROP 1 LAST VALUE 33OHM
J 0
(-2550 9850);
DISPLAY 1.212766 (-2550 9850);
PAINT GREEN (-2550 9850);
FORCEPROP 0 LAST PACKAGE 0402
J 0
(-2850 9900);
DISPLAY 1.021277 (-2850 9900);
FORCEPROP 2 LAST CDS_LIB passive
J 0
(-2800 9850);
DISPLAY INVISIBLE (-2800 9850);
FORCEPROP 1 LAST CDS_LMAN_SYM_OUTLINE -50,50,100,-50
J 0
(-2800 9850);
DISPLAY 0.468085 (-2800 9850);
PAINT GREEN (-2800 9850);
DISPLAY INVISIBLE (-2800 9850);
FORCEPROP 1 LAST CLS_PN G155-133R0-01
J 0
(-2936 10050);
DISPLAY 1.212766 (-2936 10050);
PAINT GREEN (-2936 10050);
DISPLAY INVISIBLE (-2936 10050);
FORCEPROP 1 LAST TOLERANCE 1%
J 0
(-2997 10105);
DISPLAY 1.212766 (-2997 10105);
PAINT GREEN (-2997 10105);
DISPLAY INVISIBLE (-2997 10105);
FORCEPROP 1 LAST PATH I148
J 0
(-2997 9955);
DISPLAY 1.212766 (-2997 9955);
PAINT GREEN (-2997 9955);
DISPLAY INVISIBLE (-2997 9955);
FORCEADD RESISTOR..1
(-2800 8300);
FORCEPROP 1 LAST LOCATION R392
J 2
(-2950 8300);
DISPLAY 1.212766 (-2950 8300);
PAINT GREEN (-2950 8300);
FORCEPROP 0 LAST $SEC 1
J 0
(-2650 8450);
DISPLAY 0.680851 (-2650 8450);
PAINT MONO (-2650 8450);
DISPLAY INVISIBLE (-2650 8450);
FORCEPROP 0 LAST CDS_SEC 1
J 0
(-2650 8450);
DISPLAY 1.021277 (-2650 8450);
DISPLAY INVISIBLE (-2650 8450);
FORCEPROP 0 LASTPIN (-2900 8300) $PN 1
J 2
(-2910 8310);
DISPLAY 0.680851 (-2910 8310);
PAINT MONO (-2910 8310);
FORCEPROP 0 LASTPIN (-2650 8300) $PN 2
J 0
(-2640 8310);
DISPLAY 0.680851 (-2640 8310);
PAINT MONO (-2640 8310);
FORCEPROP 0 LAST PACKAGE 0402
J 0
(-2850 8350);
DISPLAY 1.021277 (-2850 8350);
FORCEPROP 1 LAST VALUE 33OHM
J 0
(-2550 8300);
DISPLAY 1.212766 (-2550 8300);
PAINT GREEN (-2550 8300);
FORCEPROP 1 LAST CDS_LMAN_SYM_OUTLINE -50,50,100,-50
J 0
(-2800 8300);
DISPLAY 0.468085 (-2800 8300);
PAINT GREEN (-2800 8300);
DISPLAY INVISIBLE (-2800 8300);
FORCEPROP 2 LAST CDS_LIB passive
J 0
(-2800 8300);
DISPLAY INVISIBLE (-2800 8300);
FORCEPROP 1 LAST CLS_PN G155-133R0-01
J 0
(-2936 8500);
DISPLAY 1.212766 (-2936 8500);
PAINT GREEN (-2936 8500);
DISPLAY INVISIBLE (-2936 8500);
FORCEPROP 1 LAST TOLERANCE 1%
J 0
(-2997 8555);
DISPLAY 1.212766 (-2997 8555);
PAINT GREEN (-2997 8555);
DISPLAY INVISIBLE (-2997 8555);
FORCEPROP 1 LAST PATH I149
J 0
(-2997 8405);
DISPLAY 1.212766 (-2997 8405);
PAINT GREEN (-2997 8405);
DISPLAY INVISIBLE (-2997 8405);
FORCEADD RESISTOR..1
(-2800 7700);
FORCEPROP 1 LAST LOCATION R391
J 2
(-2950 7700);
DISPLAY 1.212766 (-2950 7700);
PAINT GREEN (-2950 7700);
FORCEPROP 0 LAST $SEC 1
J 0
(-2650 7850);
DISPLAY 0.680851 (-2650 7850);
PAINT MONO (-2650 7850);
DISPLAY INVISIBLE (-2650 7850);
FORCEPROP 0 LAST CDS_SEC 1
J 0
(-2650 7850);
DISPLAY 1.021277 (-2650 7850);
DISPLAY INVISIBLE (-2650 7850);
FORCEPROP 0 LASTPIN (-2900 7700) $PN 1
J 2
(-2910 7710);
DISPLAY 0.680851 (-2910 7710);
PAINT MONO (-2910 7710);
FORCEPROP 0 LASTPIN (-2650 7700) $PN 2
J 0
(-2640 7710);
DISPLAY 0.680851 (-2640 7710);
PAINT MONO (-2640 7710);
FORCEPROP 0 LAST PACKAGE 0402
J 0
(-2850 7750);
DISPLAY 1.021277 (-2850 7750);
FORCEPROP 1 LAST VALUE 33OHM
J 0
(-2550 7700);
DISPLAY 1.212766 (-2550 7700);
PAINT GREEN (-2550 7700);
FORCEPROP 1 LAST CLS_PN G155-133R0-01
J 0
(-2936 7900);
DISPLAY 1.212766 (-2936 7900);
PAINT GREEN (-2936 7900);
DISPLAY INVISIBLE (-2936 7900);
FORCEPROP 1 LAST CDS_LMAN_SYM_OUTLINE -50,50,100,-50
J 0
(-2800 7700);
DISPLAY 0.468085 (-2800 7700);
PAINT GREEN (-2800 7700);
DISPLAY INVISIBLE (-2800 7700);
FORCEPROP 2 LAST CDS_LIB passive
J 0
(-2800 7700);
DISPLAY INVISIBLE (-2800 7700);
FORCEPROP 1 LAST TOLERANCE 1%
J 0
(-2997 7955);
DISPLAY 1.212766 (-2997 7955);
PAINT GREEN (-2997 7955);
DISPLAY INVISIBLE (-2997 7955);
FORCEPROP 1 LAST PATH I150
J 0
(-2997 7805);
DISPLAY 1.212766 (-2997 7805);
PAINT GREEN (-2997 7805);
DISPLAY INVISIBLE (-2997 7805);
FORCEADD RESISTOR..1
(-2800 8000);
FORCEPROP 1 LAST LOCATION R393
J 2
(-2950 8000);
DISPLAY 1.212766 (-2950 8000);
PAINT GREEN (-2950 8000);
FORCEPROP 0 LAST $SEC 1
J 0
(-2650 8150);
DISPLAY 0.680851 (-2650 8150);
PAINT MONO (-2650 8150);
DISPLAY INVISIBLE (-2650 8150);
FORCEPROP 0 LAST CDS_SEC 1
J 0
(-2650 8150);
DISPLAY 1.021277 (-2650 8150);
DISPLAY INVISIBLE (-2650 8150);
FORCEPROP 0 LASTPIN (-2900 8000) $PN 1
J 2
(-2910 8010);
DISPLAY 0.680851 (-2910 8010);
PAINT MONO (-2910 8010);
FORCEPROP 0 LASTPIN (-2650 8000) $PN 2
J 0
(-2640 8010);
DISPLAY 0.680851 (-2640 8010);
PAINT MONO (-2640 8010);
FORCEPROP 0 LAST PACKAGE 0402
J 0
(-2850 8050);
DISPLAY 1.021277 (-2850 8050);
FORCEPROP 1 LAST VALUE 33OHM
J 0
(-2550 8000);
DISPLAY 1.212766 (-2550 8000);
PAINT GREEN (-2550 8000);
FORCEPROP 1 LAST PATH I151
J 0
(-2997 8105);
DISPLAY 1.212766 (-2997 8105);
PAINT GREEN (-2997 8105);
DISPLAY INVISIBLE (-2997 8105);
FORCEPROP 1 LAST TOLERANCE 1%
J 0
(-2997 8255);
DISPLAY 1.212766 (-2997 8255);
PAINT GREEN (-2997 8255);
DISPLAY INVISIBLE (-2997 8255);
FORCEPROP 2 LAST CDS_LIB passive
J 0
(-2800 8000);
DISPLAY INVISIBLE (-2800 8000);
FORCEPROP 1 LAST CDS_LMAN_SYM_OUTLINE -50,50,100,-50
J 0
(-2800 8000);
DISPLAY 0.468085 (-2800 8000);
PAINT GREEN (-2800 8000);
DISPLAY INVISIBLE (-2800 8000);
FORCEPROP 1 LAST CLS_PN G155-133R0-01
J 0
(-2936 8200);
DISPLAY 1.212766 (-2936 8200);
PAINT GREEN (-2936 8200);
DISPLAY INVISIBLE (-2936 8200);
FORCEADD RESISTOR..1
(-2800 6750);
FORCEPROP 1 LAST LOCATION R395
J 2
(-2950 6750);
DISPLAY 1.212766 (-2950 6750);
PAINT GREEN (-2950 6750);
FORCEPROP 0 LAST $SEC 1
J 0
(-2650 6900);
DISPLAY 0.680851 (-2650 6900);
PAINT MONO (-2650 6900);
DISPLAY INVISIBLE (-2650 6900);
FORCEPROP 0 LAST CDS_SEC 1
J 0
(-2650 6900);
DISPLAY 1.021277 (-2650 6900);
DISPLAY INVISIBLE (-2650 6900);
FORCEPROP 0 LASTPIN (-2900 6750) $PN 1
J 2
(-2910 6760);
DISPLAY 0.680851 (-2910 6760);
PAINT MONO (-2910 6760);
FORCEPROP 0 LASTPIN (-2650 6750) $PN 2
J 0
(-2640 6760);
DISPLAY 0.680851 (-2640 6760);
PAINT MONO (-2640 6760);
FORCEPROP 0 LAST PACKAGE 0402
J 0
(-2850 6800);
DISPLAY 1.021277 (-2850 6800);
FORCEPROP 1 LAST VALUE 33OHM
J 0
(-2550 6750);
DISPLAY 1.212766 (-2550 6750);
PAINT GREEN (-2550 6750);
FORCEPROP 1 LAST CDS_LMAN_SYM_OUTLINE -50,50,100,-50
J 0
(-2800 6750);
DISPLAY 0.468085 (-2800 6750);
PAINT GREEN (-2800 6750);
DISPLAY INVISIBLE (-2800 6750);
FORCEPROP 2 LAST CDS_LIB passive
J 0
(-2800 6750);
DISPLAY INVISIBLE (-2800 6750);
FORCEPROP 1 LAST CLS_PN G155-133R0-01
J 0
(-2936 6950);
DISPLAY 1.212766 (-2936 6950);
PAINT GREEN (-2936 6950);
DISPLAY INVISIBLE (-2936 6950);
FORCEPROP 1 LAST TOLERANCE 1%
J 0
(-2997 7005);
DISPLAY 1.212766 (-2997 7005);
PAINT GREEN (-2997 7005);
DISPLAY INVISIBLE (-2997 7005);
FORCEPROP 1 LAST PATH I152
J 0
(-2997 6855);
DISPLAY 1.212766 (-2997 6855);
PAINT GREEN (-2997 6855);
DISPLAY INVISIBLE (-2997 6855);
FORCEADD RESISTOR..1
(-2800 6150);
FORCEPROP 1 LAST LOCATION R394
J 2
(-2950 6150);
DISPLAY 1.212766 (-2950 6150);
PAINT GREEN (-2950 6150);
FORCEPROP 0 LAST $SEC 1
J 0
(-2650 6300);
DISPLAY 0.680851 (-2650 6300);
PAINT MONO (-2650 6300);
DISPLAY INVISIBLE (-2650 6300);
FORCEPROP 0 LAST CDS_SEC 1
J 0
(-2650 6300);
DISPLAY 1.021277 (-2650 6300);
DISPLAY INVISIBLE (-2650 6300);
FORCEPROP 0 LASTPIN (-2900 6150) $PN 1
J 2
(-2910 6160);
DISPLAY 0.680851 (-2910 6160);
PAINT MONO (-2910 6160);
FORCEPROP 0 LASTPIN (-2650 6150) $PN 2
J 0
(-2640 6160);
DISPLAY 0.680851 (-2640 6160);
PAINT MONO (-2640 6160);
FORCEPROP 0 LAST PACKAGE 0402
J 0
(-2850 6200);
DISPLAY 1.021277 (-2850 6200);
FORCEPROP 1 LAST VALUE 33OHM
J 0
(-2550 6150);
DISPLAY 1.212766 (-2550 6150);
PAINT GREEN (-2550 6150);
FORCEPROP 1 LAST CLS_PN G155-133R0-01
J 0
(-2936 6350);
DISPLAY 1.212766 (-2936 6350);
PAINT GREEN (-2936 6350);
DISPLAY INVISIBLE (-2936 6350);
FORCEPROP 1 LAST CDS_LMAN_SYM_OUTLINE -50,50,100,-50
J 0
(-2800 6150);
DISPLAY 0.468085 (-2800 6150);
PAINT GREEN (-2800 6150);
DISPLAY INVISIBLE (-2800 6150);
FORCEPROP 2 LAST CDS_LIB passive
J 0
(-2800 6150);
DISPLAY INVISIBLE (-2800 6150);
FORCEPROP 1 LAST TOLERANCE 1%
J 0
(-2997 6405);
DISPLAY 1.212766 (-2997 6405);
PAINT GREEN (-2997 6405);
DISPLAY INVISIBLE (-2997 6405);
FORCEPROP 1 LAST PATH I153
J 0
(-2997 6255);
DISPLAY 1.212766 (-2997 6255);
PAINT GREEN (-2997 6255);
DISPLAY INVISIBLE (-2997 6255);
FORCEADD RESISTOR..1
(-2800 6450);
FORCEPROP 1 LAST LOCATION R396
J 2
(-2950 6450);
DISPLAY 1.212766 (-2950 6450);
PAINT GREEN (-2950 6450);
FORCEPROP 0 LAST $SEC 1
J 0
(-2650 6600);
DISPLAY 0.680851 (-2650 6600);
PAINT MONO (-2650 6600);
DISPLAY INVISIBLE (-2650 6600);
FORCEPROP 0 LAST CDS_SEC 1
J 0
(-2650 6600);
DISPLAY 1.021277 (-2650 6600);
DISPLAY INVISIBLE (-2650 6600);
FORCEPROP 0 LASTPIN (-2900 6450) $PN 1
J 2
(-2910 6460);
DISPLAY 0.680851 (-2910 6460);
PAINT MONO (-2910 6460);
FORCEPROP 0 LASTPIN (-2650 6450) $PN 2
J 0
(-2640 6460);
DISPLAY 0.680851 (-2640 6460);
PAINT MONO (-2640 6460);
FORCEPROP 0 LAST PACKAGE 0402
J 0
(-2850 6500);
DISPLAY 1.021277 (-2850 6500);
FORCEPROP 1 LAST VALUE 33OHM
J 0
(-2550 6450);
DISPLAY 1.212766 (-2550 6450);
PAINT GREEN (-2550 6450);
FORCEPROP 1 LAST PATH I154
J 0
(-2997 6555);
DISPLAY 1.212766 (-2997 6555);
PAINT GREEN (-2997 6555);
DISPLAY INVISIBLE (-2997 6555);
FORCEPROP 1 LAST TOLERANCE 1%
J 0
(-2997 6705);
DISPLAY 1.212766 (-2997 6705);
PAINT GREEN (-2997 6705);
DISPLAY INVISIBLE (-2997 6705);
FORCEPROP 2 LAST CDS_LIB passive
J 0
(-2800 6450);
DISPLAY INVISIBLE (-2800 6450);
FORCEPROP 1 LAST CDS_LMAN_SYM_OUTLINE -50,50,100,-50
J 0
(-2800 6450);
DISPLAY 0.468085 (-2800 6450);
PAINT GREEN (-2800 6450);
DISPLAY INVISIBLE (-2800 6450);
FORCEPROP 1 LAST CLS_PN G155-133R0-01
J 0
(-2936 6650);
DISPLAY 1.212766 (-2936 6650);
PAINT GREEN (-2936 6650);
DISPLAY INVISIBLE (-2936 6650);
FORCEADD RESISTOR..1
(-2750 5200);
FORCEPROP 1 LAST LOCATION R398
J 2
(-2900 5200);
DISPLAY 1.212766 (-2900 5200);
PAINT GREEN (-2900 5200);
FORCEPROP 0 LAST $SEC 1
J 0
(-2600 5350);
DISPLAY 0.680851 (-2600 5350);
PAINT MONO (-2600 5350);
DISPLAY INVISIBLE (-2600 5350);
FORCEPROP 0 LAST CDS_SEC 1
J 0
(-2600 5350);
DISPLAY 1.021277 (-2600 5350);
DISPLAY INVISIBLE (-2600 5350);
FORCEPROP 0 LASTPIN (-2850 5200) $PN 1
J 2
(-2860 5210);
DISPLAY 0.680851 (-2860 5210);
PAINT MONO (-2860 5210);
FORCEPROP 0 LASTPIN (-2600 5200) $PN 2
J 0
(-2590 5210);
DISPLAY 0.680851 (-2590 5210);
PAINT MONO (-2590 5210);
FORCEPROP 0 LAST PACKAGE 0402
J 0
(-2800 5100);
DISPLAY 1.021277 (-2800 5100);
FORCEPROP 1 LAST VALUE 33OHM
J 0
(-2500 5200);
DISPLAY 1.212766 (-2500 5200);
PAINT GREEN (-2500 5200);
FORCEPROP 2 LAST CDS_LIB passive
J 0
(-2750 5200);
DISPLAY INVISIBLE (-2750 5200);
FORCEPROP 1 LAST CDS_LMAN_SYM_OUTLINE -50,50,100,-50
J 0
(-2750 5200);
DISPLAY 0.468085 (-2750 5200);
PAINT GREEN (-2750 5200);
DISPLAY INVISIBLE (-2750 5200);
FORCEPROP 1 LAST CLS_PN G155-133R0-01
J 0
(-2886 5400);
DISPLAY 1.212766 (-2886 5400);
PAINT GREEN (-2886 5400);
DISPLAY INVISIBLE (-2886 5400);
FORCEPROP 1 LAST TOLERANCE 1%
J 0
(-2947 5455);
DISPLAY 1.212766 (-2947 5455);
PAINT GREEN (-2947 5455);
DISPLAY INVISIBLE (-2947 5455);
FORCEPROP 1 LAST PATH I155
J 0
(-2947 5305);
DISPLAY 1.212766 (-2947 5305);
PAINT GREEN (-2947 5305);
DISPLAY INVISIBLE (-2947 5305);
FORCEADD RESISTOR..1
(-2750 4600);
FORCEPROP 1 LAST LOCATION R397
J 2
(-2900 4600);
DISPLAY 1.212766 (-2900 4600);
PAINT GREEN (-2900 4600);
FORCEPROP 0 LAST $SEC 1
J 0
(-2600 4750);
DISPLAY 0.680851 (-2600 4750);
PAINT MONO (-2600 4750);
DISPLAY INVISIBLE (-2600 4750);
FORCEPROP 0 LAST CDS_SEC 1
J 0
(-2600 4750);
DISPLAY 1.021277 (-2600 4750);
DISPLAY INVISIBLE (-2600 4750);
FORCEPROP 0 LASTPIN (-2850 4600) $PN 1
J 2
(-2860 4610);
DISPLAY 0.680851 (-2860 4610);
PAINT MONO (-2860 4610);
FORCEPROP 0 LASTPIN (-2600 4600) $PN 2
J 0
(-2590 4610);
DISPLAY 0.680851 (-2590 4610);
PAINT MONO (-2590 4610);
FORCEPROP 1 LAST VALUE 33OHM
J 0
(-2500 4600);
DISPLAY 1.212766 (-2500 4600);
PAINT GREEN (-2500 4600);
FORCEPROP 0 LAST PACKAGE 0402
J 0
(-2800 4500);
DISPLAY 1.021277 (-2800 4500);
FORCEPROP 1 LAST CLS_PN G155-133R0-01
J 0
(-2886 4800);
DISPLAY 1.212766 (-2886 4800);
PAINT GREEN (-2886 4800);
DISPLAY INVISIBLE (-2886 4800);
FORCEPROP 2 LAST CDS_LIB passive
J 0
(-2750 4600);
DISPLAY INVISIBLE (-2750 4600);
FORCEPROP 1 LAST CDS_LMAN_SYM_OUTLINE -50,50,100,-50
J 0
(-2750 4600);
DISPLAY 0.468085 (-2750 4600);
PAINT GREEN (-2750 4600);
DISPLAY INVISIBLE (-2750 4600);
FORCEPROP 1 LAST TOLERANCE 1%
J 0
(-2947 4855);
DISPLAY 1.212766 (-2947 4855);
PAINT GREEN (-2947 4855);
DISPLAY INVISIBLE (-2947 4855);
FORCEPROP 1 LAST PATH I156
J 0
(-2947 4705);
DISPLAY 1.212766 (-2947 4705);
PAINT GREEN (-2947 4705);
DISPLAY INVISIBLE (-2947 4705);
FORCEADD RESISTOR..1
(-2750 4900);
FORCEPROP 1 LAST LOCATION R399
J 2
(-2900 4900);
DISPLAY 1.212766 (-2900 4900);
PAINT GREEN (-2900 4900);
FORCEPROP 0 LAST $SEC 1
J 0
(-2600 5050);
DISPLAY 0.680851 (-2600 5050);
PAINT MONO (-2600 5050);
DISPLAY INVISIBLE (-2600 5050);
FORCEPROP 0 LAST CDS_SEC 1
J 0
(-2600 5050);
DISPLAY 1.021277 (-2600 5050);
DISPLAY INVISIBLE (-2600 5050);
FORCEPROP 0 LASTPIN (-2850 4900) $PN 1
J 2
(-2860 4910);
DISPLAY 0.680851 (-2860 4910);
PAINT MONO (-2860 4910);
FORCEPROP 0 LASTPIN (-2600 4900) $PN 2
J 0
(-2590 4910);
DISPLAY 0.680851 (-2590 4910);
PAINT MONO (-2590 4910);
FORCEPROP 1 LAST VALUE 33OHM
J 0
(-2500 4900);
DISPLAY 1.212766 (-2500 4900);
PAINT GREEN (-2500 4900);
FORCEPROP 0 LAST PACKAGE 0402
J 0
(-2800 4800);
DISPLAY 1.021277 (-2800 4800);
FORCEPROP 1 LAST PATH I157
J 0
(-2947 5005);
DISPLAY 1.212766 (-2947 5005);
PAINT GREEN (-2947 5005);
DISPLAY INVISIBLE (-2947 5005);
FORCEPROP 1 LAST TOLERANCE 1%
J 0
(-2947 5155);
DISPLAY 1.212766 (-2947 5155);
PAINT GREEN (-2947 5155);
DISPLAY INVISIBLE (-2947 5155);
FORCEPROP 1 LAST CDS_LMAN_SYM_OUTLINE -50,50,100,-50
J 0
(-2750 4900);
DISPLAY 0.468085 (-2750 4900);
PAINT GREEN (-2750 4900);
DISPLAY INVISIBLE (-2750 4900);
FORCEPROP 2 LAST CDS_LIB passive
J 0
(-2750 4900);
DISPLAY INVISIBLE (-2750 4900);
FORCEPROP 1 LAST CLS_PN G155-133R0-01
J 0
(-2886 5100);
DISPLAY 1.212766 (-2886 5100);
PAINT GREEN (-2886 5100);
DISPLAY INVISIBLE (-2886 5100);
FORCEADD OFFPAGE_OUT..1
R 4
(-4550 10600);
FORCEPROP 2 LAST $XR0 12D12> 
J 0
(-4764 10600);
DISPLAY 0.638298 (-4764 10600);
PAINT MONO (-4764 10600);
FORCEPROP 1 LAST BODY_TYPE COMMENT
R 2
J 0
(-4560 10465);
DISPLAY 0.808511 (-4560 10465);
PAINT GREEN (-4560 10465);
DISPLAY INVISIBLE (-4560 10465);
FORCEPROP 1 LAST CDS_LMAN_SYM_OUTLINE -50,50,50,-50
R 2
J 0
(-4550 10600);
DISPLAY 0.468085 (-4550 10600);
PAINT GREEN (-4550 10600);
DISPLAY INVISIBLE (-4550 10600);
FORCEPROP 2 LAST CDS_LIB cls
J 0
(-4550 10600);
DISPLAY INVISIBLE (-4550 10600);
FORCEPROP 1 LAST OFFPAGE TRUE
R 2
J 0
(-4560 10545);
DISPLAY 0.808511 (-4560 10545);
PAINT GREEN (-4560 10545);
DISPLAY INVISIBLE (-4560 10545);
FORCEPROP 2 LAST PATH I159
J 0
(-4700 10650);
DISPLAY 1.021277 (-4700 10650);
DISPLAY INVISIBLE (-4700 10650);
FORCEADD RESISTOR..1
(-2800 10600);
FORCEPROP 1 LAST $LOCATION R124
J 2
(-3000 10600);
DISPLAY 1.212766 (-3000 10600);
PAINT GREEN (-3000 10600);
FORCEPROP 0 LAST CDS_LOCATION R124
J 0
(-2550 10700);
DISPLAY 1.021277 (-2550 10700);
DISPLAY INVISIBLE (-2550 10700);
FORCEPROP 0 LAST $SEC 1
J 0
(-2550 10700);
DISPLAY 0.680851 (-2550 10700);
PAINT MONO (-2550 10700);
DISPLAY INVISIBLE (-2550 10700);
FORCEPROP 0 LAST CDS_SEC 1
J 0
(-2550 10700);
DISPLAY 1.021277 (-2550 10700);
DISPLAY INVISIBLE (-2550 10700);
FORCEPROP 0 LASTPIN (-2900 10600) $PN 1
J 2
(-2910 10610);
DISPLAY 0.680851 (-2910 10610);
PAINT MONO (-2910 10610);
FORCEPROP 0 LASTPIN (-2650 10600) $PN 2
J 0
(-2640 10610);
DISPLAY 0.680851 (-2640 10610);
PAINT MONO (-2640 10610);
FORCEPROP 0 LAST NO_ASSY TRUE
J 0
(-2550 10650);
DISPLAY 1.021277 (-2550 10650);
DISPLAY BOTH (-2550 10650);
FORCEPROP 0 LAST PACKAGE 0402
J 0
(-2850 10650);
DISPLAY 1.021277 (-2850 10650);
FORCEPROP 1 LAST VALUE 100OHM
J 0
(-2550 10600);
DISPLAY 1.212766 (-2550 10600);
PAINT GREEN (-2550 10600);
FORCEPROP 1 LAST PATH I160
J 0
(-2997 10705);
DISPLAY 1.212766 (-2997 10705);
PAINT GREEN (-2997 10705);
DISPLAY INVISIBLE (-2997 10705);
FORCEPROP 1 LAST TOLERANCE 1%
J 0
(-2997 10855);
DISPLAY 1.212766 (-2997 10855);
PAINT GREEN (-2997 10855);
DISPLAY INVISIBLE (-2997 10855);
FORCEPROP 1 LAST CLS_PN G155-11000-01
J 0
(-2936 10800);
DISPLAY 1.212766 (-2936 10800);
PAINT GREEN (-2936 10800);
DISPLAY INVISIBLE (-2936 10800);
FORCEPROP 2 LAST CDS_LIB passive
J 0
(-2800 10600);
DISPLAY INVISIBLE (-2800 10600);
FORCEPROP 1 LAST CDS_LMAN_SYM_OUTLINE -50,50,100,-50
J 0
(-2800 10600);
DISPLAY 0.468085 (-2800 10600);
PAINT GREEN (-2800 10600);
DISPLAY INVISIBLE (-2800 10600);
FORCEADD RESISTOR..1
(-2800 11200);
FORCEPROP 1 LAST $LOCATION R125
J 2
(-3000 11200);
DISPLAY 1.212766 (-3000 11200);
PAINT GREEN (-3000 11200);
FORCEPROP 0 LAST CDS_LOCATION R125
J 0
(-2550 11300);
DISPLAY 1.021277 (-2550 11300);
DISPLAY INVISIBLE (-2550 11300);
FORCEPROP 0 LAST $SEC 1
J 0
(-2550 11300);
DISPLAY 0.680851 (-2550 11300);
PAINT MONO (-2550 11300);
DISPLAY INVISIBLE (-2550 11300);
FORCEPROP 0 LAST CDS_SEC 1
J 0
(-2550 11300);
DISPLAY 1.021277 (-2550 11300);
DISPLAY INVISIBLE (-2550 11300);
FORCEPROP 0 LASTPIN (-2900 11200) $PN 1
J 2
(-2910 11210);
DISPLAY 0.680851 (-2910 11210);
PAINT MONO (-2910 11210);
FORCEPROP 0 LASTPIN (-2650 11200) $PN 2
J 0
(-2640 11210);
DISPLAY 0.680851 (-2640 11210);
PAINT MONO (-2640 11210);
FORCEPROP 0 LAST NO_ASSY TRUE
J 0
(-2550 11250);
DISPLAY 1.021277 (-2550 11250);
DISPLAY BOTH (-2550 11250);
FORCEPROP 0 LAST PACKAGE 0402
J 0
(-2850 11250);
DISPLAY 1.021277 (-2850 11250);
FORCEPROP 1 LAST VALUE 100OHM
J 0
(-2550 11200);
DISPLAY 1.212766 (-2550 11200);
PAINT GREEN (-2550 11200);
FORCEPROP 1 LAST PATH I161
J 0
(-2997 11305);
DISPLAY 1.212766 (-2997 11305);
PAINT GREEN (-2997 11305);
DISPLAY INVISIBLE (-2997 11305);
FORCEPROP 1 LAST TOLERANCE 1%
J 0
(-2997 11455);
DISPLAY 1.212766 (-2997 11455);
PAINT GREEN (-2997 11455);
DISPLAY INVISIBLE (-2997 11455);
FORCEPROP 1 LAST CDS_LMAN_SYM_OUTLINE -50,50,100,-50
J 0
(-2800 11200);
DISPLAY 0.468085 (-2800 11200);
PAINT GREEN (-2800 11200);
DISPLAY INVISIBLE (-2800 11200);
FORCEPROP 2 LAST CDS_LIB passive
J 0
(-2800 11200);
DISPLAY INVISIBLE (-2800 11200);
FORCEPROP 1 LAST CLS_PN G155-11000-01
J 0
(-2936 11400);
DISPLAY 1.212766 (-2936 11400);
PAINT GREEN (-2936 11400);
DISPLAY INVISIBLE (-2936 11400);
FORCEADD OFFPAGE_OUT..1
R 4
(-4550 11200);
FORCEPROP 2 LAST $XR0 12D12> 
J 0
(-4764 11200);
DISPLAY 0.638298 (-4764 11200);
PAINT MONO (-4764 11200);
FORCEPROP 2 LAST CDS_LIB cls
J 0
(-4550 11200);
DISPLAY INVISIBLE (-4550 11200);
FORCEPROP 1 LAST CDS_LMAN_SYM_OUTLINE -50,50,50,-50
R 2
J 0
(-4550 11200);
DISPLAY 0.468085 (-4550 11200);
PAINT GREEN (-4550 11200);
DISPLAY INVISIBLE (-4550 11200);
FORCEPROP 1 LAST BODY_TYPE COMMENT
R 2
J 0
(-4560 11065);
DISPLAY 0.808511 (-4560 11065);
PAINT GREEN (-4560 11065);
DISPLAY INVISIBLE (-4560 11065);
FORCEPROP 1 LAST OFFPAGE TRUE
R 2
J 0
(-4560 11145);
DISPLAY 0.808511 (-4560 11145);
PAINT GREEN (-4560 11145);
DISPLAY INVISIBLE (-4560 11145);
FORCEPROP 2 LAST PATH I162
J 0
(-4700 11250);
DISPLAY 1.021277 (-4700 11250);
DISPLAY INVISIBLE (-4700 11250);
FORCEADD RESISTOR..1
(-2800 10900);
FORCEPROP 1 LAST $LOCATION R272
J 2
(-3000 10900);
DISPLAY 1.212766 (-3000 10900);
PAINT GREEN (-3000 10900);
FORCEPROP 0 LAST CDS_LOCATION R272
J 0
(-2550 11000);
DISPLAY 1.021277 (-2550 11000);
DISPLAY INVISIBLE (-2550 11000);
FORCEPROP 0 LAST $SEC 1
J 0
(-2550 11000);
DISPLAY 0.680851 (-2550 11000);
PAINT MONO (-2550 11000);
DISPLAY INVISIBLE (-2550 11000);
FORCEPROP 0 LAST CDS_SEC 1
J 0
(-2550 11000);
DISPLAY 1.021277 (-2550 11000);
DISPLAY INVISIBLE (-2550 11000);
FORCEPROP 0 LASTPIN (-2900 10900) $PN 1
J 2
(-2910 10910);
DISPLAY 0.680851 (-2910 10910);
PAINT MONO (-2910 10910);
FORCEPROP 0 LASTPIN (-2650 10900) $PN 2
J 0
(-2640 10910);
DISPLAY 0.680851 (-2640 10910);
PAINT MONO (-2640 10910);
FORCEPROP 0 LAST PACKAGE 0402
J 0
(-2850 10950);
DISPLAY 1.021277 (-2850 10950);
FORCEPROP 0 LAST NO_ASSY TRUE
J 0
(-2550 10950);
DISPLAY 1.021277 (-2550 10950);
DISPLAY BOTH (-2550 10950);
FORCEPROP 1 LAST VALUE 100OHM
J 0
(-2550 10900);
DISPLAY 1.212766 (-2550 10900);
PAINT GREEN (-2550 10900);
FORCEPROP 1 LAST PATH I163
J 0
(-2997 11005);
DISPLAY 1.212766 (-2997 11005);
PAINT GREEN (-2997 11005);
DISPLAY INVISIBLE (-2997 11005);
FORCEPROP 1 LAST TOLERANCE 1%
J 0
(-2997 11155);
DISPLAY 1.212766 (-2997 11155);
PAINT GREEN (-2997 11155);
DISPLAY INVISIBLE (-2997 11155);
FORCEPROP 2 LAST CDS_LIB passive
J 0
(-2800 10900);
DISPLAY INVISIBLE (-2800 10900);
FORCEPROP 1 LAST CDS_LMAN_SYM_OUTLINE -50,50,100,-50
J 0
(-2800 10900);
DISPLAY 0.468085 (-2800 10900);
PAINT GREEN (-2800 10900);
DISPLAY INVISIBLE (-2800 10900);
FORCEPROP 1 LAST CLS_PN G155-11000-01
J 0
(-2936 11100);
DISPLAY 1.212766 (-2936 11100);
PAINT GREEN (-2936 11100);
DISPLAY INVISIBLE (-2936 11100);
FORCEADD OFFPAGE_OUT..1
R 4
(-4550 10900);
FORCEPROP 2 LAST $XR0 12D12> 
J 0
(-4764 10900);
DISPLAY 0.638298 (-4764 10900);
PAINT MONO (-4764 10900);
FORCEPROP 2 LAST CDS_LIB cls
J 0
(-4550 10900);
DISPLAY INVISIBLE (-4550 10900);
FORCEPROP 1 LAST CDS_LMAN_SYM_OUTLINE -50,50,50,-50
R 2
J 0
(-4550 10900);
DISPLAY 0.468085 (-4550 10900);
PAINT GREEN (-4550 10900);
DISPLAY INVISIBLE (-4550 10900);
FORCEPROP 1 LAST BODY_TYPE COMMENT
R 2
J 0
(-4560 10765);
DISPLAY 0.808511 (-4560 10765);
PAINT GREEN (-4560 10765);
DISPLAY INVISIBLE (-4560 10765);
FORCEPROP 1 LAST OFFPAGE TRUE
R 2
J 0
(-4560 10845);
DISPLAY 0.808511 (-4560 10845);
PAINT GREEN (-4560 10845);
DISPLAY INVISIBLE (-4560 10845);
FORCEPROP 2 LAST PATH I164
J 0
(-4700 10950);
DISPLAY 1.021277 (-4700 10950);
DISPLAY INVISIBLE (-4700 10950);
FORCEADD RESISTOR..1
(-2800 9100);
FORCEPROP 1 LAST $LOCATION R273
J 2
(-2950 9100);
DISPLAY 1.212766 (-2950 9100);
PAINT GREEN (-2950 9100);
FORCEPROP 0 LAST CDS_LOCATION R273
J 0
(-2550 9200);
DISPLAY 1.021277 (-2550 9200);
DISPLAY INVISIBLE (-2550 9200);
FORCEPROP 0 LAST $SEC 1
J 0
(-2550 9200);
DISPLAY 0.680851 (-2550 9200);
PAINT MONO (-2550 9200);
DISPLAY INVISIBLE (-2550 9200);
FORCEPROP 0 LAST CDS_SEC 1
J 0
(-2550 9200);
DISPLAY 1.021277 (-2550 9200);
DISPLAY INVISIBLE (-2550 9200);
FORCEPROP 0 LASTPIN (-2900 9100) $PN 1
J 2
(-2910 9110);
DISPLAY 0.680851 (-2910 9110);
PAINT MONO (-2910 9110);
FORCEPROP 0 LASTPIN (-2650 9100) $PN 2
J 0
(-2640 9110);
DISPLAY 0.680851 (-2640 9110);
PAINT MONO (-2640 9110);
FORCEPROP 0 LAST NO_ASSY TRUE
J 0
(-2550 9150);
DISPLAY 1.021277 (-2550 9150);
DISPLAY BOTH (-2550 9150);
FORCEPROP 0 LAST PACKAGE 0402
J 0
(-2850 9150);
DISPLAY 1.021277 (-2850 9150);
FORCEPROP 1 LAST VALUE 100OHM
J 0
(-2550 9100);
DISPLAY 1.212766 (-2550 9100);
PAINT GREEN (-2550 9100);
FORCEPROP 1 LAST CDS_LMAN_SYM_OUTLINE -50,50,100,-50
J 0
(-2800 9100);
DISPLAY 0.468085 (-2800 9100);
PAINT GREEN (-2800 9100);
DISPLAY INVISIBLE (-2800 9100);
FORCEPROP 2 LAST CDS_LIB passive
J 0
(-2800 9100);
DISPLAY INVISIBLE (-2800 9100);
FORCEPROP 1 LAST CLS_PN G155-11000-01
J 0
(-2936 9300);
DISPLAY 1.212766 (-2936 9300);
PAINT GREEN (-2936 9300);
DISPLAY INVISIBLE (-2936 9300);
FORCEPROP 1 LAST TOLERANCE 1%
J 0
(-2997 9355);
DISPLAY 1.212766 (-2997 9355);
PAINT GREEN (-2997 9355);
DISPLAY INVISIBLE (-2997 9355);
FORCEPROP 1 LAST PATH I165
J 0
(-2997 9205);
DISPLAY 1.212766 (-2997 9205);
PAINT GREEN (-2997 9205);
DISPLAY INVISIBLE (-2997 9205);
FORCEADD OFFPAGE_OUT..1
R 4
(-4550 9100);
FORCEPROP 2 LAST $XR0 12D12> 
J 0
(-4764 9100);
DISPLAY 0.638298 (-4764 9100);
PAINT MONO (-4764 9100);
FORCEPROP 1 LAST BODY_TYPE COMMENT
R 2
J 0
(-4560 8965);
DISPLAY 0.808511 (-4560 8965);
PAINT GREEN (-4560 8965);
DISPLAY INVISIBLE (-4560 8965);
FORCEPROP 1 LAST CDS_LMAN_SYM_OUTLINE -50,50,50,-50
R 2
J 0
(-4550 9100);
DISPLAY 0.468085 (-4550 9100);
PAINT GREEN (-4550 9100);
DISPLAY INVISIBLE (-4550 9100);
FORCEPROP 2 LAST CDS_LIB cls
J 0
(-4550 9100);
DISPLAY INVISIBLE (-4550 9100);
FORCEPROP 1 LAST OFFPAGE TRUE
R 2
J 0
(-4560 9045);
DISPLAY 0.808511 (-4560 9045);
PAINT GREEN (-4560 9045);
DISPLAY INVISIBLE (-4560 9045);
FORCEPROP 2 LAST PATH I166
J 0
(-4700 9150);
DISPLAY 1.021277 (-4700 9150);
DISPLAY INVISIBLE (-4700 9150);
FORCEADD OFFPAGE_OUT..1
R 4
(-4550 7550);
FORCEPROP 2 LAST $XR0 12F12> 
J 0
(-4764 7550);
DISPLAY 0.638298 (-4764 7550);
PAINT MONO (-4764 7550);
FORCEPROP 2 LAST CDS_LIB cls
J 0
(-4550 7550);
DISPLAY INVISIBLE (-4550 7550);
FORCEPROP 1 LAST CDS_LMAN_SYM_OUTLINE -50,50,50,-50
R 2
J 0
(-4550 7550);
DISPLAY 0.468085 (-4550 7550);
PAINT GREEN (-4550 7550);
DISPLAY INVISIBLE (-4550 7550);
FORCEPROP 1 LAST BODY_TYPE COMMENT
R 2
J 0
(-4560 7415);
DISPLAY 0.808511 (-4560 7415);
PAINT GREEN (-4560 7415);
DISPLAY INVISIBLE (-4560 7415);
FORCEPROP 1 LAST OFFPAGE TRUE
R 2
J 0
(-4560 7495);
DISPLAY 0.808511 (-4560 7495);
PAINT GREEN (-4560 7495);
DISPLAY INVISIBLE (-4560 7495);
FORCEPROP 2 LAST PATH I167
J 0
(-4700 7600);
DISPLAY 1.021277 (-4700 7600);
DISPLAY INVISIBLE (-4700 7600);
FORCEADD RESISTOR..1
(-2800 7550);
FORCEPROP 1 LAST $LOCATION R374
J 2
(-2950 7550);
DISPLAY 1.212766 (-2950 7550);
PAINT GREEN (-2950 7550);
FORCEPROP 0 LAST CDS_LOCATION R374
J 0
(-2550 7650);
DISPLAY 1.021277 (-2550 7650);
DISPLAY INVISIBLE (-2550 7650);
FORCEPROP 0 LAST $SEC 1
J 0
(-2550 7650);
DISPLAY 0.680851 (-2550 7650);
PAINT MONO (-2550 7650);
DISPLAY INVISIBLE (-2550 7650);
FORCEPROP 0 LAST CDS_SEC 1
J 0
(-2550 7650);
DISPLAY 1.021277 (-2550 7650);
DISPLAY INVISIBLE (-2550 7650);
FORCEPROP 0 LASTPIN (-2900 7550) $PN 1
J 2
(-2910 7560);
DISPLAY 0.680851 (-2910 7560);
PAINT MONO (-2910 7560);
FORCEPROP 0 LASTPIN (-2650 7550) $PN 2
J 0
(-2640 7560);
DISPLAY 0.680851 (-2640 7560);
PAINT MONO (-2640 7560);
FORCEPROP 0 LAST NO_ASSY TRUE
J 0
(-2550 7600);
DISPLAY 1.021277 (-2550 7600);
DISPLAY BOTH (-2550 7600);
FORCEPROP 0 LAST PACKAGE 0402
J 0
(-2850 7600);
DISPLAY 1.021277 (-2850 7600);
FORCEPROP 1 LAST VALUE 100OHM
J 0
(-2550 7550);
DISPLAY 1.212766 (-2550 7550);
PAINT GREEN (-2550 7550);
FORCEPROP 2 LAST CDS_LIB passive
J 0
(-2800 7550);
DISPLAY INVISIBLE (-2800 7550);
FORCEPROP 1 LAST CDS_LMAN_SYM_OUTLINE -50,50,100,-50
J 0
(-2800 7550);
DISPLAY 0.468085 (-2800 7550);
PAINT GREEN (-2800 7550);
DISPLAY INVISIBLE (-2800 7550);
FORCEPROP 1 LAST CLS_PN G155-11000-01
J 0
(-2936 7750);
DISPLAY 1.212766 (-2936 7750);
PAINT GREEN (-2936 7750);
DISPLAY INVISIBLE (-2936 7750);
FORCEPROP 1 LAST TOLERANCE 1%
J 0
(-2997 7805);
DISPLAY 1.212766 (-2997 7805);
PAINT GREEN (-2997 7805);
DISPLAY INVISIBLE (-2997 7805);
FORCEPROP 1 LAST PATH I168
J 0
(-2997 7655);
DISPLAY 1.212766 (-2997 7655);
PAINT GREEN (-2997 7655);
DISPLAY INVISIBLE (-2997 7655);
FORCEADD OFFPAGE_OUT..1
R 4
(-4500 4450);
FORCEPROP 2 LAST $XR0 12G12> 
J 0
(-4714 4450);
DISPLAY 0.638298 (-4714 4450);
PAINT MONO (-4714 4450);
FORCEPROP 2 LAST CDS_LIB cls
J 0
(-4500 4450);
DISPLAY INVISIBLE (-4500 4450);
FORCEPROP 1 LAST CDS_LMAN_SYM_OUTLINE -50,50,50,-50
R 2
J 0
(-4500 4450);
DISPLAY 0.468085 (-4500 4450);
PAINT GREEN (-4500 4450);
DISPLAY INVISIBLE (-4500 4450);
FORCEPROP 1 LAST BODY_TYPE COMMENT
R 2
J 0
(-4510 4315);
DISPLAY 0.808511 (-4510 4315);
PAINT GREEN (-4510 4315);
DISPLAY INVISIBLE (-4510 4315);
FORCEPROP 1 LAST OFFPAGE TRUE
R 2
J 0
(-4510 4395);
DISPLAY 0.808511 (-4510 4395);
PAINT GREEN (-4510 4395);
DISPLAY INVISIBLE (-4510 4395);
FORCEPROP 2 LAST PATH I169
J 0
(-4650 4500);
DISPLAY 1.021277 (-4650 4500);
DISPLAY INVISIBLE (-4650 4500);
FORCEADD RESISTOR..1
(-2750 4450);
FORCEPROP 1 LAST $LOCATION R425
J 2
(-2900 4450);
DISPLAY 1.212766 (-2900 4450);
PAINT GREEN (-2900 4450);
FORCEPROP 0 LAST CDS_LOCATION R425
J 0
(-2500 4550);
DISPLAY 1.021277 (-2500 4550);
DISPLAY INVISIBLE (-2500 4550);
FORCEPROP 0 LAST $SEC 1
J 0
(-2500 4550);
DISPLAY 0.680851 (-2500 4550);
PAINT MONO (-2500 4550);
DISPLAY INVISIBLE (-2500 4550);
FORCEPROP 0 LAST CDS_SEC 1
J 0
(-2500 4550);
DISPLAY 1.021277 (-2500 4550);
DISPLAY INVISIBLE (-2500 4550);
FORCEPROP 0 LASTPIN (-2850 4450) $PN 1
J 2
(-2860 4460);
DISPLAY 0.680851 (-2860 4460);
PAINT MONO (-2860 4460);
FORCEPROP 0 LASTPIN (-2600 4450) $PN 2
J 0
(-2590 4460);
DISPLAY 0.680851 (-2590 4460);
PAINT MONO (-2590 4460);
FORCEPROP 0 LAST NO_ASSY TRUE
J 0
(-2500 4500);
DISPLAY 1.021277 (-2500 4500);
DISPLAY BOTH (-2500 4500);
FORCEPROP 1 LAST VALUE 100OHM
J 0
(-2500 4450);
DISPLAY 1.212766 (-2500 4450);
PAINT GREEN (-2500 4450);
FORCEPROP 0 LAST PACKAGE 0402
J 0
(-2800 4500);
DISPLAY 1.021277 (-2800 4500);
FORCEPROP 1 LAST CDS_LMAN_SYM_OUTLINE -50,50,100,-50
J 0
(-2750 4450);
DISPLAY 0.468085 (-2750 4450);
PAINT GREEN (-2750 4450);
DISPLAY INVISIBLE (-2750 4450);
FORCEPROP 2 LAST CDS_LIB passive
J 0
(-2750 4450);
DISPLAY INVISIBLE (-2750 4450);
FORCEPROP 1 LAST CLS_PN G155-11000-01
J 0
(-2886 4650);
DISPLAY 1.212766 (-2886 4650);
PAINT GREEN (-2886 4650);
DISPLAY INVISIBLE (-2886 4650);
FORCEPROP 1 LAST TOLERANCE 1%
J 0
(-2947 4705);
DISPLAY 1.212766 (-2947 4705);
PAINT GREEN (-2947 4705);
DISPLAY INVISIBLE (-2947 4705);
FORCEPROP 1 LAST PATH I170
J 0
(-2947 4555);
DISPLAY 1.212766 (-2947 4555);
PAINT GREEN (-2947 4555);
DISPLAY INVISIBLE (-2947 4555);
FORCEADD RESISTOR..1
(-2800 9700);
FORCEPROP 1 LAST $LOCATION R274
J 2
(-2950 9700);
DISPLAY 1.212766 (-2950 9700);
PAINT GREEN (-2950 9700);
FORCEPROP 0 LAST CDS_LOCATION R274
J 0
(-2550 9800);
DISPLAY 1.021277 (-2550 9800);
DISPLAY INVISIBLE (-2550 9800);
FORCEPROP 0 LAST $SEC 1
J 0
(-2550 9800);
DISPLAY 0.680851 (-2550 9800);
PAINT MONO (-2550 9800);
DISPLAY INVISIBLE (-2550 9800);
FORCEPROP 0 LAST CDS_SEC 1
J 0
(-2550 9800);
DISPLAY 1.021277 (-2550 9800);
DISPLAY INVISIBLE (-2550 9800);
FORCEPROP 0 LASTPIN (-2900 9700) $PN 1
J 2
(-2910 9710);
DISPLAY 0.680851 (-2910 9710);
PAINT MONO (-2910 9710);
FORCEPROP 0 LASTPIN (-2650 9700) $PN 2
J 0
(-2640 9710);
DISPLAY 0.680851 (-2640 9710);
PAINT MONO (-2640 9710);
FORCEPROP 0 LAST NO_ASSY TRUE
J 0
(-2550 9750);
DISPLAY 1.021277 (-2550 9750);
DISPLAY BOTH (-2550 9750);
FORCEPROP 0 LAST PACKAGE 0402
J 0
(-2850 9750);
DISPLAY 1.021277 (-2850 9750);
FORCEPROP 1 LAST VALUE 100OHM
J 0
(-2550 9700);
DISPLAY 1.212766 (-2550 9700);
PAINT GREEN (-2550 9700);
FORCEPROP 1 LAST PATH I171
J 0
(-2997 9805);
DISPLAY 1.212766 (-2997 9805);
PAINT GREEN (-2997 9805);
DISPLAY INVISIBLE (-2997 9805);
FORCEPROP 1 LAST TOLERANCE 1%
J 0
(-2997 9955);
DISPLAY 1.212766 (-2997 9955);
PAINT GREEN (-2997 9955);
DISPLAY INVISIBLE (-2997 9955);
FORCEPROP 1 LAST CDS_LMAN_SYM_OUTLINE -50,50,100,-50
J 0
(-2800 9700);
DISPLAY 0.468085 (-2800 9700);
PAINT GREEN (-2800 9700);
DISPLAY INVISIBLE (-2800 9700);
FORCEPROP 2 LAST CDS_LIB passive
J 0
(-2800 9700);
DISPLAY INVISIBLE (-2800 9700);
FORCEPROP 1 LAST CLS_PN G155-11000-01
J 0
(-2936 9900);
DISPLAY 1.212766 (-2936 9900);
PAINT GREEN (-2936 9900);
DISPLAY INVISIBLE (-2936 9900);
FORCEADD OFFPAGE_OUT..1
R 4
(-4550 9700);
FORCEPROP 2 LAST $XR0 12D12> 
J 0
(-4764 9700);
DISPLAY 0.638298 (-4764 9700);
PAINT MONO (-4764 9700);
FORCEPROP 2 LAST CDS_LIB cls
J 0
(-4550 9700);
DISPLAY INVISIBLE (-4550 9700);
FORCEPROP 1 LAST CDS_LMAN_SYM_OUTLINE -50,50,50,-50
R 2
J 0
(-4550 9700);
DISPLAY 0.468085 (-4550 9700);
PAINT GREEN (-4550 9700);
DISPLAY INVISIBLE (-4550 9700);
FORCEPROP 1 LAST BODY_TYPE COMMENT
R 2
J 0
(-4560 9565);
DISPLAY 0.808511 (-4560 9565);
PAINT GREEN (-4560 9565);
DISPLAY INVISIBLE (-4560 9565);
FORCEPROP 1 LAST OFFPAGE TRUE
R 2
J 0
(-4560 9645);
DISPLAY 0.808511 (-4560 9645);
PAINT GREEN (-4560 9645);
DISPLAY INVISIBLE (-4560 9645);
FORCEPROP 2 LAST PATH I172
J 0
(-4700 9750);
DISPLAY 1.021277 (-4700 9750);
DISPLAY INVISIBLE (-4700 9750);
FORCEADD OFFPAGE_OUT..1
R 4
(-4550 8150);
FORCEPROP 2 LAST $XR0 12F12> 
J 0
(-4764 8150);
DISPLAY 0.638298 (-4764 8150);
PAINT MONO (-4764 8150);
FORCEPROP 1 LAST BODY_TYPE COMMENT
R 2
J 0
(-4560 8015);
DISPLAY 0.808511 (-4560 8015);
PAINT GREEN (-4560 8015);
DISPLAY INVISIBLE (-4560 8015);
FORCEPROP 1 LAST CDS_LMAN_SYM_OUTLINE -50,50,50,-50
R 2
J 0
(-4550 8150);
DISPLAY 0.468085 (-4550 8150);
PAINT GREEN (-4550 8150);
DISPLAY INVISIBLE (-4550 8150);
FORCEPROP 2 LAST CDS_LIB cls
J 0
(-4550 8150);
DISPLAY INVISIBLE (-4550 8150);
FORCEPROP 1 LAST OFFPAGE TRUE
R 2
J 0
(-4560 8095);
DISPLAY 0.808511 (-4560 8095);
PAINT GREEN (-4560 8095);
DISPLAY INVISIBLE (-4560 8095);
FORCEPROP 2 LAST PATH I173
J 0
(-4700 8200);
DISPLAY 1.021277 (-4700 8200);
DISPLAY INVISIBLE (-4700 8200);
FORCEADD RESISTOR..1
(-2800 8150);
FORCEPROP 1 LAST $LOCATION R375
J 2
(-2950 8150);
DISPLAY 1.212766 (-2950 8150);
PAINT GREEN (-2950 8150);
FORCEPROP 0 LAST CDS_LOCATION R375
J 0
(-2550 8250);
DISPLAY 1.021277 (-2550 8250);
DISPLAY INVISIBLE (-2550 8250);
FORCEPROP 0 LAST $SEC 1
J 0
(-2550 8250);
DISPLAY 0.680851 (-2550 8250);
PAINT MONO (-2550 8250);
DISPLAY INVISIBLE (-2550 8250);
FORCEPROP 0 LAST CDS_SEC 1
J 0
(-2550 8250);
DISPLAY 1.021277 (-2550 8250);
DISPLAY INVISIBLE (-2550 8250);
FORCEPROP 0 LASTPIN (-2900 8150) $PN 1
J 2
(-2910 8160);
DISPLAY 0.680851 (-2910 8160);
PAINT MONO (-2910 8160);
FORCEPROP 0 LASTPIN (-2650 8150) $PN 2
J 0
(-2640 8160);
DISPLAY 0.680851 (-2640 8160);
PAINT MONO (-2640 8160);
FORCEPROP 0 LAST NO_ASSY TRUE
J 0
(-2550 8200);
DISPLAY 1.021277 (-2550 8200);
DISPLAY BOTH (-2550 8200);
FORCEPROP 0 LAST PACKAGE 0402
J 0
(-2850 8200);
DISPLAY 1.021277 (-2850 8200);
FORCEPROP 1 LAST VALUE 100OHM
J 0
(-2550 8150);
DISPLAY 1.212766 (-2550 8150);
PAINT GREEN (-2550 8150);
FORCEPROP 1 LAST PATH I174
J 0
(-2997 8255);
DISPLAY 1.212766 (-2997 8255);
PAINT GREEN (-2997 8255);
DISPLAY INVISIBLE (-2997 8255);
FORCEPROP 1 LAST TOLERANCE 1%
J 0
(-2997 8405);
DISPLAY 1.212766 (-2997 8405);
PAINT GREEN (-2997 8405);
DISPLAY INVISIBLE (-2997 8405);
FORCEPROP 2 LAST CDS_LIB passive
J 0
(-2800 8150);
DISPLAY INVISIBLE (-2800 8150);
FORCEPROP 1 LAST CDS_LMAN_SYM_OUTLINE -50,50,100,-50
J 0
(-2800 8150);
DISPLAY 0.468085 (-2800 8150);
PAINT GREEN (-2800 8150);
DISPLAY INVISIBLE (-2800 8150);
FORCEPROP 1 LAST CLS_PN G155-11000-01
J 0
(-2936 8350);
DISPLAY 1.212766 (-2936 8350);
PAINT GREEN (-2936 8350);
DISPLAY INVISIBLE (-2936 8350);
FORCEADD OFFPAGE_OUT..1
R 4
(-4550 6600);
FORCEPROP 2 LAST $XR0 12F12> 
J 0
(-4764 6600);
DISPLAY 0.638298 (-4764 6600);
PAINT MONO (-4764 6600);
FORCEPROP 1 LAST BODY_TYPE COMMENT
R 2
J 0
(-4560 6465);
DISPLAY 0.808511 (-4560 6465);
PAINT GREEN (-4560 6465);
DISPLAY INVISIBLE (-4560 6465);
FORCEPROP 1 LAST CDS_LMAN_SYM_OUTLINE -50,50,50,-50
R 2
J 0
(-4550 6600);
DISPLAY 0.468085 (-4550 6600);
PAINT GREEN (-4550 6600);
DISPLAY INVISIBLE (-4550 6600);
FORCEPROP 2 LAST CDS_LIB cls
J 0
(-4550 6600);
DISPLAY INVISIBLE (-4550 6600);
FORCEPROP 1 LAST OFFPAGE TRUE
R 2
J 0
(-4560 6545);
DISPLAY 0.808511 (-4560 6545);
PAINT GREEN (-4560 6545);
DISPLAY INVISIBLE (-4560 6545);
FORCEPROP 2 LAST PATH I175
J 0
(-4700 6650);
DISPLAY 1.021277 (-4700 6650);
DISPLAY INVISIBLE (-4700 6650);
FORCEADD RESISTOR..1
(-2800 6600);
FORCEPROP 1 LAST $LOCATION R401
J 2
(-2950 6600);
DISPLAY 1.212766 (-2950 6600);
PAINT GREEN (-2950 6600);
FORCEPROP 0 LAST CDS_LOCATION R401
J 0
(-2550 6700);
DISPLAY 1.021277 (-2550 6700);
DISPLAY INVISIBLE (-2550 6700);
FORCEPROP 0 LAST $SEC 1
J 0
(-2550 6700);
DISPLAY 0.680851 (-2550 6700);
PAINT MONO (-2550 6700);
DISPLAY INVISIBLE (-2550 6700);
FORCEPROP 0 LAST CDS_SEC 1
J 0
(-2550 6700);
DISPLAY 1.021277 (-2550 6700);
DISPLAY INVISIBLE (-2550 6700);
FORCEPROP 0 LASTPIN (-2900 6600) $PN 1
J 2
(-2910 6610);
DISPLAY 0.680851 (-2910 6610);
PAINT MONO (-2910 6610);
FORCEPROP 0 LASTPIN (-2650 6600) $PN 2
J 0
(-2640 6610);
DISPLAY 0.680851 (-2640 6610);
PAINT MONO (-2640 6610);
FORCEPROP 0 LAST NO_ASSY TRUE
J 0
(-2550 6650);
DISPLAY 1.021277 (-2550 6650);
DISPLAY BOTH (-2550 6650);
FORCEPROP 0 LAST PACKAGE 0402
J 0
(-2850 6650);
DISPLAY 1.021277 (-2850 6650);
FORCEPROP 1 LAST VALUE 100OHM
J 0
(-2550 6600);
DISPLAY 1.212766 (-2550 6600);
PAINT GREEN (-2550 6600);
FORCEPROP 1 LAST PATH I176
J 0
(-2997 6705);
DISPLAY 1.212766 (-2997 6705);
PAINT GREEN (-2997 6705);
DISPLAY INVISIBLE (-2997 6705);
FORCEPROP 1 LAST TOLERANCE 1%
J 0
(-2997 6855);
DISPLAY 1.212766 (-2997 6855);
PAINT GREEN (-2997 6855);
DISPLAY INVISIBLE (-2997 6855);
FORCEPROP 2 LAST CDS_LIB passive
J 0
(-2800 6600);
DISPLAY INVISIBLE (-2800 6600);
FORCEPROP 1 LAST CDS_LMAN_SYM_OUTLINE -50,50,100,-50
J 0
(-2800 6600);
DISPLAY 0.468085 (-2800 6600);
PAINT GREEN (-2800 6600);
DISPLAY INVISIBLE (-2800 6600);
FORCEPROP 1 LAST CLS_PN G155-11000-01
J 0
(-2936 6800);
DISPLAY 1.212766 (-2936 6800);
PAINT GREEN (-2936 6800);
DISPLAY INVISIBLE (-2936 6800);
FORCEADD RESISTOR..1
(-2800 6000);
FORCEPROP 1 LAST $LOCATION R400
J 2
(-2950 6000);
DISPLAY 1.212766 (-2950 6000);
PAINT GREEN (-2950 6000);
FORCEPROP 0 LAST CDS_LOCATION R400
J 0
(-2550 6100);
DISPLAY 1.021277 (-2550 6100);
DISPLAY INVISIBLE (-2550 6100);
FORCEPROP 0 LAST $SEC 1
J 0
(-2550 6100);
DISPLAY 0.680851 (-2550 6100);
PAINT MONO (-2550 6100);
DISPLAY INVISIBLE (-2550 6100);
FORCEPROP 0 LAST CDS_SEC 1
J 0
(-2550 6100);
DISPLAY 1.021277 (-2550 6100);
DISPLAY INVISIBLE (-2550 6100);
FORCEPROP 0 LASTPIN (-2900 6000) $PN 1
J 2
(-2910 6010);
DISPLAY 0.680851 (-2910 6010);
PAINT MONO (-2910 6010);
FORCEPROP 0 LASTPIN (-2650 6000) $PN 2
J 0
(-2640 6010);
DISPLAY 0.680851 (-2640 6010);
PAINT MONO (-2640 6010);
FORCEPROP 0 LAST NO_ASSY TRUE
J 0
(-2550 6050);
DISPLAY 1.021277 (-2550 6050);
DISPLAY BOTH (-2550 6050);
FORCEPROP 0 LAST PACKAGE 0402
J 0
(-2850 6050);
DISPLAY 1.021277 (-2850 6050);
FORCEPROP 1 LAST VALUE 100OHM
J 0
(-2550 6000);
DISPLAY 1.212766 (-2550 6000);
PAINT GREEN (-2550 6000);
FORCEPROP 1 LAST CDS_LMAN_SYM_OUTLINE -50,50,100,-50
J 0
(-2800 6000);
DISPLAY 0.468085 (-2800 6000);
PAINT GREEN (-2800 6000);
DISPLAY INVISIBLE (-2800 6000);
FORCEPROP 2 LAST CDS_LIB passive
J 0
(-2800 6000);
DISPLAY INVISIBLE (-2800 6000);
FORCEPROP 1 LAST CLS_PN G155-11000-01
J 0
(-2936 6200);
DISPLAY 1.212766 (-2936 6200);
PAINT GREEN (-2936 6200);
DISPLAY INVISIBLE (-2936 6200);
FORCEPROP 1 LAST TOLERANCE 1%
J 0
(-2997 6255);
DISPLAY 1.212766 (-2997 6255);
PAINT GREEN (-2997 6255);
DISPLAY INVISIBLE (-2997 6255);
FORCEPROP 1 LAST PATH I177
J 0
(-2997 6105);
DISPLAY 1.212766 (-2997 6105);
PAINT GREEN (-2997 6105);
DISPLAY INVISIBLE (-2997 6105);
FORCEADD OFFPAGE_OUT..1
R 4
(-4550 6000);
FORCEPROP 2 LAST $XR0 12F12> 
J 0
(-4764 6000);
DISPLAY 0.638298 (-4764 6000);
PAINT MONO (-4764 6000);
FORCEPROP 1 LAST BODY_TYPE COMMENT
R 2
J 0
(-4560 5865);
DISPLAY 0.808511 (-4560 5865);
PAINT GREEN (-4560 5865);
DISPLAY INVISIBLE (-4560 5865);
FORCEPROP 1 LAST CDS_LMAN_SYM_OUTLINE -50,50,50,-50
R 2
J 0
(-4550 6000);
DISPLAY 0.468085 (-4550 6000);
PAINT GREEN (-4550 6000);
DISPLAY INVISIBLE (-4550 6000);
FORCEPROP 2 LAST CDS_LIB cls
J 0
(-4550 6000);
DISPLAY INVISIBLE (-4550 6000);
FORCEPROP 1 LAST OFFPAGE TRUE
R 2
J 0
(-4560 5945);
DISPLAY 0.808511 (-4560 5945);
PAINT GREEN (-4560 5945);
DISPLAY INVISIBLE (-4560 5945);
FORCEPROP 2 LAST PATH I178
J 0
(-4700 6050);
DISPLAY 1.021277 (-4700 6050);
DISPLAY INVISIBLE (-4700 6050);
FORCEADD RESISTOR..1
(-2750 5050);
FORCEPROP 1 LAST $LOCATION R426
J 2
(-2900 5050);
DISPLAY 1.212766 (-2900 5050);
PAINT GREEN (-2900 5050);
FORCEPROP 0 LAST CDS_LOCATION R426
J 0
(-2500 5150);
DISPLAY 1.021277 (-2500 5150);
DISPLAY INVISIBLE (-2500 5150);
FORCEPROP 0 LAST $SEC 1
J 0
(-2500 5150);
DISPLAY 0.680851 (-2500 5150);
PAINT MONO (-2500 5150);
DISPLAY INVISIBLE (-2500 5150);
FORCEPROP 0 LAST CDS_SEC 1
J 0
(-2500 5150);
DISPLAY 1.021277 (-2500 5150);
DISPLAY INVISIBLE (-2500 5150);
FORCEPROP 0 LASTPIN (-2850 5050) $PN 1
J 2
(-2860 5060);
DISPLAY 0.680851 (-2860 5060);
PAINT MONO (-2860 5060);
FORCEPROP 0 LASTPIN (-2600 5050) $PN 2
J 0
(-2590 5060);
DISPLAY 0.680851 (-2590 5060);
PAINT MONO (-2590 5060);
FORCEPROP 0 LAST NO_ASSY TRUE
J 0
(-2500 5100);
DISPLAY 1.021277 (-2500 5100);
DISPLAY BOTH (-2500 5100);
FORCEPROP 0 LAST PACKAGE 0402
J 0
(-2800 5100);
DISPLAY 1.021277 (-2800 5100);
FORCEPROP 1 LAST VALUE 100OHM
J 0
(-2500 5050);
DISPLAY 1.212766 (-2500 5050);
PAINT GREEN (-2500 5050);
FORCEPROP 1 LAST PATH I179
J 0
(-2947 5155);
DISPLAY 1.212766 (-2947 5155);
PAINT GREEN (-2947 5155);
DISPLAY INVISIBLE (-2947 5155);
FORCEPROP 1 LAST TOLERANCE 1%
J 0
(-2947 5305);
DISPLAY 1.212766 (-2947 5305);
PAINT GREEN (-2947 5305);
DISPLAY INVISIBLE (-2947 5305);
FORCEPROP 1 LAST CDS_LMAN_SYM_OUTLINE -50,50,100,-50
J 0
(-2750 5050);
DISPLAY 0.468085 (-2750 5050);
PAINT GREEN (-2750 5050);
DISPLAY INVISIBLE (-2750 5050);
FORCEPROP 2 LAST CDS_LIB passive
J 0
(-2750 5050);
DISPLAY INVISIBLE (-2750 5050);
FORCEPROP 1 LAST CLS_PN G155-11000-01
J 0
(-2886 5250);
DISPLAY 1.212766 (-2886 5250);
PAINT GREEN (-2886 5250);
DISPLAY INVISIBLE (-2886 5250);
FORCEADD OFFPAGE_OUT..1
R 4
(-4500 5050);
FORCEPROP 2 LAST $XR0 12G12> 
J 0
(-4714 5050);
DISPLAY 0.638298 (-4714 5050);
PAINT MONO (-4714 5050);
FORCEPROP 1 LAST BODY_TYPE COMMENT
R 2
J 0
(-4510 4915);
DISPLAY 0.808511 (-4510 4915);
PAINT GREEN (-4510 4915);
DISPLAY INVISIBLE (-4510 4915);
FORCEPROP 1 LAST CDS_LMAN_SYM_OUTLINE -50,50,50,-50
R 2
J 0
(-4500 5050);
DISPLAY 0.468085 (-4500 5050);
PAINT GREEN (-4500 5050);
DISPLAY INVISIBLE (-4500 5050);
FORCEPROP 2 LAST CDS_LIB cls
J 0
(-4500 5050);
DISPLAY INVISIBLE (-4500 5050);
FORCEPROP 1 LAST OFFPAGE TRUE
R 2
J 0
(-4510 4995);
DISPLAY 0.808511 (-4510 4995);
PAINT GREEN (-4510 4995);
DISPLAY INVISIBLE (-4510 4995);
FORCEPROP 2 LAST PATH I180
J 0
(-4650 5100);
DISPLAY 1.021277 (-4650 5100);
DISPLAY INVISIBLE (-4650 5100);
FORCEADD RESISTOR..1
(-2800 9400);
FORCEPROP 1 LAST $LOCATION R373
J 2
(-2950 9400);
DISPLAY 1.212766 (-2950 9400);
PAINT GREEN (-2950 9400);
FORCEPROP 0 LAST CDS_LOCATION R373
J 0
(-2550 9500);
DISPLAY 1.021277 (-2550 9500);
DISPLAY INVISIBLE (-2550 9500);
FORCEPROP 0 LAST $SEC 1
J 0
(-2550 9500);
DISPLAY 0.680851 (-2550 9500);
PAINT MONO (-2550 9500);
DISPLAY INVISIBLE (-2550 9500);
FORCEPROP 0 LAST CDS_SEC 1
J 0
(-2550 9500);
DISPLAY 1.021277 (-2550 9500);
DISPLAY INVISIBLE (-2550 9500);
FORCEPROP 0 LASTPIN (-2900 9400) $PN 1
J 2
(-2910 9410);
DISPLAY 0.680851 (-2910 9410);
PAINT MONO (-2910 9410);
FORCEPROP 0 LASTPIN (-2650 9400) $PN 2
J 0
(-2640 9410);
DISPLAY 0.680851 (-2640 9410);
PAINT MONO (-2640 9410);
FORCEPROP 0 LAST PACKAGE 0402
J 0
(-2850 9450);
DISPLAY 1.021277 (-2850 9450);
FORCEPROP 0 LAST NO_ASSY TRUE
J 0
(-2550 9450);
DISPLAY 1.021277 (-2550 9450);
DISPLAY BOTH (-2550 9450);
FORCEPROP 1 LAST VALUE 100OHM
J 0
(-2550 9400);
DISPLAY 1.212766 (-2550 9400);
PAINT GREEN (-2550 9400);
FORCEPROP 1 LAST PATH I181
J 0
(-2997 9505);
DISPLAY 1.212766 (-2997 9505);
PAINT GREEN (-2997 9505);
DISPLAY INVISIBLE (-2997 9505);
FORCEPROP 1 LAST TOLERANCE 1%
J 0
(-2997 9655);
DISPLAY 1.212766 (-2997 9655);
PAINT GREEN (-2997 9655);
DISPLAY INVISIBLE (-2997 9655);
FORCEPROP 2 LAST CDS_LIB passive
J 0
(-2800 9400);
DISPLAY INVISIBLE (-2800 9400);
FORCEPROP 1 LAST CDS_LMAN_SYM_OUTLINE -50,50,100,-50
J 0
(-2800 9400);
DISPLAY 0.468085 (-2800 9400);
PAINT GREEN (-2800 9400);
DISPLAY INVISIBLE (-2800 9400);
FORCEPROP 1 LAST CLS_PN G155-11000-01
J 0
(-2936 9600);
DISPLAY 1.212766 (-2936 9600);
PAINT GREEN (-2936 9600);
DISPLAY INVISIBLE (-2936 9600);
FORCEADD OFFPAGE_OUT..1
R 4
(-4550 9400);
FORCEPROP 2 LAST $XR0 12D12> 
J 0
(-4764 9400);
DISPLAY 0.638298 (-4764 9400);
PAINT MONO (-4764 9400);
FORCEPROP 2 LAST CDS_LIB cls
J 0
(-4550 9400);
DISPLAY INVISIBLE (-4550 9400);
FORCEPROP 1 LAST CDS_LMAN_SYM_OUTLINE -50,50,50,-50
R 2
J 0
(-4550 9400);
DISPLAY 0.468085 (-4550 9400);
PAINT GREEN (-4550 9400);
DISPLAY INVISIBLE (-4550 9400);
FORCEPROP 1 LAST BODY_TYPE COMMENT
R 2
J 0
(-4560 9265);
DISPLAY 0.808511 (-4560 9265);
PAINT GREEN (-4560 9265);
DISPLAY INVISIBLE (-4560 9265);
FORCEPROP 1 LAST OFFPAGE TRUE
R 2
J 0
(-4560 9345);
DISPLAY 0.808511 (-4560 9345);
PAINT GREEN (-4560 9345);
DISPLAY INVISIBLE (-4560 9345);
FORCEPROP 2 LAST PATH I182
J 0
(-4700 9450);
DISPLAY 1.021277 (-4700 9450);
DISPLAY INVISIBLE (-4700 9450);
FORCEADD OFFPAGE_OUT..1
R 4
(-4550 7850);
FORCEPROP 2 LAST $XR0 12F12> 
J 0
(-4764 7850);
DISPLAY 0.638298 (-4764 7850);
PAINT MONO (-4764 7850);
FORCEPROP 1 LAST BODY_TYPE COMMENT
R 2
J 0
(-4560 7715);
DISPLAY 0.808511 (-4560 7715);
PAINT GREEN (-4560 7715);
DISPLAY INVISIBLE (-4560 7715);
FORCEPROP 1 LAST CDS_LMAN_SYM_OUTLINE -50,50,50,-50
R 2
J 0
(-4550 7850);
DISPLAY 0.468085 (-4550 7850);
PAINT GREEN (-4550 7850);
DISPLAY INVISIBLE (-4550 7850);
FORCEPROP 2 LAST CDS_LIB cls
J 0
(-4550 7850);
DISPLAY INVISIBLE (-4550 7850);
FORCEPROP 1 LAST OFFPAGE TRUE
R 2
J 0
(-4560 7795);
DISPLAY 0.808511 (-4560 7795);
PAINT GREEN (-4560 7795);
DISPLAY INVISIBLE (-4560 7795);
FORCEPROP 2 LAST PATH I183
J 0
(-4700 7900);
DISPLAY 1.021277 (-4700 7900);
DISPLAY INVISIBLE (-4700 7900);
FORCEADD RESISTOR..1
(-2800 7850);
FORCEPROP 1 LAST $LOCATION R376
J 2
(-2950 7850);
DISPLAY 1.212766 (-2950 7850);
PAINT GREEN (-2950 7850);
FORCEPROP 0 LAST CDS_LOCATION R376
J 0
(-2550 7950);
DISPLAY 1.021277 (-2550 7950);
DISPLAY INVISIBLE (-2550 7950);
FORCEPROP 0 LAST $SEC 1
J 0
(-2550 7950);
DISPLAY 0.680851 (-2550 7950);
PAINT MONO (-2550 7950);
DISPLAY INVISIBLE (-2550 7950);
FORCEPROP 0 LAST CDS_SEC 1
J 0
(-2550 7950);
DISPLAY 1.021277 (-2550 7950);
DISPLAY INVISIBLE (-2550 7950);
FORCEPROP 0 LASTPIN (-2900 7850) $PN 1
J 2
(-2910 7860);
DISPLAY 0.680851 (-2910 7860);
PAINT MONO (-2910 7860);
FORCEPROP 0 LASTPIN (-2650 7850) $PN 2
J 0
(-2640 7860);
DISPLAY 0.680851 (-2640 7860);
PAINT MONO (-2640 7860);
FORCEPROP 0 LAST NO_ASSY TRUE
J 0
(-2550 7900);
DISPLAY 1.021277 (-2550 7900);
DISPLAY BOTH (-2550 7900);
FORCEPROP 0 LAST PACKAGE 0402
J 0
(-2850 7900);
DISPLAY 1.021277 (-2850 7900);
FORCEPROP 1 LAST VALUE 100OHM
J 0
(-2550 7850);
DISPLAY 1.212766 (-2550 7850);
PAINT GREEN (-2550 7850);
FORCEPROP 1 LAST PATH I184
J 0
(-2997 7955);
DISPLAY 1.212766 (-2997 7955);
PAINT GREEN (-2997 7955);
DISPLAY INVISIBLE (-2997 7955);
FORCEPROP 1 LAST TOLERANCE 1%
J 0
(-2997 8105);
DISPLAY 1.212766 (-2997 8105);
PAINT GREEN (-2997 8105);
DISPLAY INVISIBLE (-2997 8105);
FORCEPROP 1 LAST CDS_LMAN_SYM_OUTLINE -50,50,100,-50
J 0
(-2800 7850);
DISPLAY 0.468085 (-2800 7850);
PAINT GREEN (-2800 7850);
DISPLAY INVISIBLE (-2800 7850);
FORCEPROP 2 LAST CDS_LIB passive
J 0
(-2800 7850);
DISPLAY INVISIBLE (-2800 7850);
FORCEPROP 1 LAST CLS_PN G155-11000-01
J 0
(-2936 8050);
DISPLAY 1.212766 (-2936 8050);
PAINT GREEN (-2936 8050);
DISPLAY INVISIBLE (-2936 8050);
FORCEADD OFFPAGE_OUT..1
R 4
(-4550 6300);
FORCEPROP 2 LAST $XR0 12F12> 
J 0
(-4764 6300);
DISPLAY 0.638298 (-4764 6300);
PAINT MONO (-4764 6300);
FORCEPROP 1 LAST BODY_TYPE COMMENT
R 2
J 0
(-4560 6165);
DISPLAY 0.808511 (-4560 6165);
PAINT GREEN (-4560 6165);
DISPLAY INVISIBLE (-4560 6165);
FORCEPROP 2 LAST CDS_LIB cls
J 0
(-4550 6300);
DISPLAY INVISIBLE (-4550 6300);
FORCEPROP 1 LAST CDS_LMAN_SYM_OUTLINE -50,50,50,-50
R 2
J 0
(-4550 6300);
DISPLAY 0.468085 (-4550 6300);
PAINT GREEN (-4550 6300);
DISPLAY INVISIBLE (-4550 6300);
FORCEPROP 1 LAST OFFPAGE TRUE
R 2
J 0
(-4560 6245);
DISPLAY 0.808511 (-4560 6245);
PAINT GREEN (-4560 6245);
DISPLAY INVISIBLE (-4560 6245);
FORCEPROP 2 LAST PATH I185
J 0
(-4700 6350);
DISPLAY 1.021277 (-4700 6350);
DISPLAY INVISIBLE (-4700 6350);
FORCEADD RESISTOR..1
(-2800 6300);
FORCEPROP 1 LAST $LOCATION R424
J 2
(-2950 6300);
DISPLAY 1.212766 (-2950 6300);
PAINT GREEN (-2950 6300);
FORCEPROP 0 LAST CDS_LOCATION R424
J 0
(-2550 6400);
DISPLAY 1.021277 (-2550 6400);
DISPLAY INVISIBLE (-2550 6400);
FORCEPROP 0 LAST $SEC 1
J 0
(-2550 6400);
DISPLAY 0.680851 (-2550 6400);
PAINT MONO (-2550 6400);
DISPLAY INVISIBLE (-2550 6400);
FORCEPROP 0 LAST CDS_SEC 1
J 0
(-2550 6400);
DISPLAY 1.021277 (-2550 6400);
DISPLAY INVISIBLE (-2550 6400);
FORCEPROP 0 LASTPIN (-2900 6300) $PN 1
J 2
(-2910 6310);
DISPLAY 0.680851 (-2910 6310);
PAINT MONO (-2910 6310);
FORCEPROP 0 LASTPIN (-2650 6300) $PN 2
J 0
(-2640 6310);
DISPLAY 0.680851 (-2640 6310);
PAINT MONO (-2640 6310);
FORCEPROP 0 LAST NO_ASSY TRUE
J 0
(-2550 6350);
DISPLAY 1.021277 (-2550 6350);
DISPLAY BOTH (-2550 6350);
FORCEPROP 0 LAST PACKAGE 0402
J 0
(-2850 6350);
DISPLAY 1.021277 (-2850 6350);
FORCEPROP 1 LAST VALUE 100OHM
J 0
(-2550 6300);
DISPLAY 1.212766 (-2550 6300);
PAINT GREEN (-2550 6300);
FORCEPROP 1 LAST PATH I186
J 0
(-2997 6405);
DISPLAY 1.212766 (-2997 6405);
PAINT GREEN (-2997 6405);
DISPLAY INVISIBLE (-2997 6405);
FORCEPROP 1 LAST TOLERANCE 1%
J 0
(-2997 6555);
DISPLAY 1.212766 (-2997 6555);
PAINT GREEN (-2997 6555);
DISPLAY INVISIBLE (-2997 6555);
FORCEPROP 1 LAST CDS_LMAN_SYM_OUTLINE -50,50,100,-50
J 0
(-2800 6300);
DISPLAY 0.468085 (-2800 6300);
PAINT GREEN (-2800 6300);
DISPLAY INVISIBLE (-2800 6300);
FORCEPROP 2 LAST CDS_LIB passive
J 0
(-2800 6300);
DISPLAY INVISIBLE (-2800 6300);
FORCEPROP 1 LAST CLS_PN G155-11000-01
J 0
(-2936 6500);
DISPLAY 1.212766 (-2936 6500);
PAINT GREEN (-2936 6500);
DISPLAY INVISIBLE (-2936 6500);
FORCEADD OFFPAGE_OUT..1
R 4
(-4500 4750);
FORCEPROP 2 LAST $XR0 12G12> 
J 0
(-4714 4750);
DISPLAY 0.638298 (-4714 4750);
PAINT MONO (-4714 4750);
FORCEPROP 1 LAST BODY_TYPE COMMENT
R 2
J 0
(-4510 4615);
DISPLAY 0.808511 (-4510 4615);
PAINT GREEN (-4510 4615);
DISPLAY INVISIBLE (-4510 4615);
FORCEPROP 1 LAST CDS_LMAN_SYM_OUTLINE -50,50,50,-50
R 2
J 0
(-4500 4750);
DISPLAY 0.468085 (-4500 4750);
PAINT GREEN (-4500 4750);
DISPLAY INVISIBLE (-4500 4750);
FORCEPROP 2 LAST CDS_LIB cls
J 0
(-4500 4750);
DISPLAY INVISIBLE (-4500 4750);
FORCEPROP 1 LAST OFFPAGE TRUE
R 2
J 0
(-4510 4695);
DISPLAY 0.808511 (-4510 4695);
PAINT GREEN (-4510 4695);
DISPLAY INVISIBLE (-4510 4695);
FORCEPROP 2 LAST PATH I187
J 0
(-4650 4800);
DISPLAY 1.021277 (-4650 4800);
DISPLAY INVISIBLE (-4650 4800);
FORCEADD RESISTOR..1
(-2750 4750);
FORCEPROP 1 LAST $LOCATION R427
J 2
(-2900 4750);
DISPLAY 1.212766 (-2900 4750);
PAINT GREEN (-2900 4750);
FORCEPROP 0 LAST CDS_LOCATION R427
J 0
(-2500 4850);
DISPLAY 1.021277 (-2500 4850);
DISPLAY INVISIBLE (-2500 4850);
FORCEPROP 0 LAST $SEC 1
J 0
(-2500 4850);
DISPLAY 0.680851 (-2500 4850);
PAINT MONO (-2500 4850);
DISPLAY INVISIBLE (-2500 4850);
FORCEPROP 0 LAST CDS_SEC 1
J 0
(-2500 4850);
DISPLAY 1.021277 (-2500 4850);
DISPLAY INVISIBLE (-2500 4850);
FORCEPROP 0 LASTPIN (-2850 4750) $PN 1
J 2
(-2860 4760);
DISPLAY 0.680851 (-2860 4760);
PAINT MONO (-2860 4760);
FORCEPROP 0 LASTPIN (-2600 4750) $PN 2
J 0
(-2590 4760);
DISPLAY 0.680851 (-2590 4760);
PAINT MONO (-2590 4760);
FORCEPROP 0 LAST NO_ASSY TRUE
J 0
(-2500 4800);
DISPLAY 1.021277 (-2500 4800);
DISPLAY BOTH (-2500 4800);
FORCEPROP 0 LAST PACKAGE 0402
J 0
(-2800 4800);
DISPLAY 1.021277 (-2800 4800);
FORCEPROP 1 LAST VALUE 100OHM
J 0
(-2500 4750);
DISPLAY 1.212766 (-2500 4750);
PAINT GREEN (-2500 4750);
FORCEPROP 1 LAST PATH I188
J 0
(-2947 4855);
DISPLAY 1.212766 (-2947 4855);
PAINT GREEN (-2947 4855);
DISPLAY INVISIBLE (-2947 4855);
FORCEPROP 1 LAST TOLERANCE 1%
J 0
(-2947 5005);
DISPLAY 1.212766 (-2947 5005);
PAINT GREEN (-2947 5005);
DISPLAY INVISIBLE (-2947 5005);
FORCEPROP 2 LAST CDS_LIB passive
J 0
(-2750 4750);
DISPLAY INVISIBLE (-2750 4750);
FORCEPROP 1 LAST CDS_LMAN_SYM_OUTLINE -50,50,100,-50
J 0
(-2750 4750);
DISPLAY 0.468085 (-2750 4750);
PAINT GREEN (-2750 4750);
DISPLAY INVISIBLE (-2750 4750);
FORCEPROP 1 LAST CLS_PN G155-11000-01
J 0
(-2886 4950);
DISPLAY 1.212766 (-2886 4950);
PAINT GREEN (-2886 4950);
DISPLAY INVISIBLE (-2886 4950);
FORCEADD RESISTOR..1
(-9250 7750);
FORCEPROP 1 LAST $LOCATION R118
J 2
(-9351 7805);
DISPLAY 1.212766 (-9351 7805);
PAINT GREEN (-9351 7805);
FORCEPROP 0 LAST CDS_LOCATION R118
J 0
(-9100 7900);
DISPLAY 1.021277 (-9100 7900);
DISPLAY INVISIBLE (-9100 7900);
FORCEPROP 0 LAST $SEC 1
J 0
(-9100 7900);
DISPLAY 0.680851 (-9100 7900);
PAINT MONO (-9100 7900);
DISPLAY INVISIBLE (-9100 7900);
FORCEPROP 0 LAST CDS_SEC 1
J 0
(-9100 7900);
DISPLAY 1.021277 (-9100 7900);
DISPLAY INVISIBLE (-9100 7900);
FORCEPROP 0 LASTPIN (-9350 7750) $PN 1
J 2
(-9360 7760);
DISPLAY 0.680851 (-9360 7760);
PAINT MONO (-9360 7760);
FORCEPROP 0 LASTPIN (-9100 7750) $PN 2
J 0
(-9090 7760);
DISPLAY 0.680851 (-9090 7760);
PAINT MONO (-9090 7760);
FORCEPROP 1 LAST VALUE 330OHM
J 0
(-9100 7800);
DISPLAY 1.212766 (-9100 7800);
PAINT GREEN (-9100 7800);
FORCEPROP 0 LAST PACKAGE 0402
J 0
(-9300 7650);
DISPLAY 1.021277 (-9300 7650);
FORCEPROP 1 LAST PATH I190
J 0
(-9447 7855);
DISPLAY 1.212766 (-9447 7855);
PAINT GREEN (-9447 7855);
DISPLAY INVISIBLE (-9447 7855);
FORCEPROP 1 LAST TOLERANCE 1%
J 0
(-9447 8005);
DISPLAY 1.212766 (-9447 8005);
PAINT GREEN (-9447 8005);
DISPLAY INVISIBLE (-9447 8005);
FORCEPROP 1 LAST CLS_PN G155-13300-01
J 0
(-9386 7950);
DISPLAY 1.212766 (-9386 7950);
PAINT GREEN (-9386 7950);
DISPLAY INVISIBLE (-9386 7950);
FORCEPROP 1 LAST CDS_LMAN_SYM_OUTLINE -50,50,100,-50
J 0
(-9250 7750);
DISPLAY 0.468085 (-9250 7750);
PAINT GREEN (-9250 7750);
DISPLAY INVISIBLE (-9250 7750);
FORCEPROP 2 LAST CDS_LIB passive
J 0
(-9250 7750);
DISPLAY INVISIBLE (-9250 7750);
FORCEADD OPTICAL..1
R 2
(-10600 7750);
FORCEPROP 1 LAST $LOCATION DS19
J 0
(-10412 7800);
DISPLAY 1.212766 (-10412 7800);
PAINT GREEN (-10412 7800);
FORCEPROP 0 LAST CDS_LOCATION DS19
J 0
(-11550 7950);
DISPLAY 1.021277 (-11550 7950);
DISPLAY INVISIBLE (-11550 7950);
FORCEPROP 0 LAST $SEC 1
J 0
(-11550 7950);
DISPLAY 0.680851 (-11550 7950);
PAINT MONO (-11550 7950);
DISPLAY INVISIBLE (-11550 7950);
FORCEPROP 0 LAST CDS_SEC 1
J 0
(-11550 7950);
DISPLAY 1.021277 (-11550 7950);
DISPLAY INVISIBLE (-11550 7950);
FORCEPROP 0 LASTPIN (-10350 7750) $PN A
J 0
(-10340 7760);
DISPLAY 0.680851 (-10340 7760);
PAINT MONO (-10340 7760);
FORCEPROP 0 LASTPIN (-10850 7750) $PN C
J 2
(-10860 7760);
DISPLAY 0.680851 (-10860 7760);
PAINT MONO (-10860 7760);
FORCEPROP 1 LAST CLS_PN G170-10143-01
J 2
(-10800 7800);
DISPLAY 1.212766 (-10800 7800);
PAINT GREEN (-10800 7800);
FORCEPROP 0 LAST PART_NUMBER LTST-C190KGKT
J 0
(-11550 7900);
DISPLAY 1.021277 (-11550 7900);
FORCEPROP 1 LAST PATH I191
J 2
(-10700 7950);
DISPLAY 1.212766 (-10700 7950);
PAINT GREEN (-10700 7950);
DISPLAY INVISIBLE (-10700 7950);
FORCEPROP 2 LASTPIN (-10350 7750) SIG_NAME UN$14$OPTICAL$I191$A
J 0
(-10340 7760);
DISPLAY 0.659574 (-10340 7760);
PAINT MONO (-10340 7760);
DISPLAY INVISIBLE (-10340 7760);
FORCEPROP 1 LAST CDS_LMAN_SYM_OUTLINE -150,100,150,-50
J 2
(-10600 7750);
DISPLAY 0.468085 (-10600 7750);
PAINT GREEN (-10600 7750);
DISPLAY INVISIBLE (-10600 7750);
FORCEPROP 2 LAST CDS_LIB discrete
J 0
(-10600 7750);
DISPLAY INVISIBLE (-10600 7750);
FORCEADD RESISTOR..1
(-9250 7400);
FORCEPROP 1 LAST $LOCATION R119
J 2
(-9351 7455);
DISPLAY 1.212766 (-9351 7455);
PAINT GREEN (-9351 7455);
FORCEPROP 0 LAST CDS_LOCATION R119
J 0
(-9100 7550);
DISPLAY 1.021277 (-9100 7550);
DISPLAY INVISIBLE (-9100 7550);
FORCEPROP 0 LAST $SEC 1
J 0
(-9100 7550);
DISPLAY 0.680851 (-9100 7550);
PAINT MONO (-9100 7550);
DISPLAY INVISIBLE (-9100 7550);
FORCEPROP 0 LAST CDS_SEC 1
J 0
(-9100 7550);
DISPLAY 1.021277 (-9100 7550);
DISPLAY INVISIBLE (-9100 7550);
FORCEPROP 0 LASTPIN (-9350 7400) $PN 1
J 2
(-9360 7410);
DISPLAY 0.680851 (-9360 7410);
PAINT MONO (-9360 7410);
FORCEPROP 0 LASTPIN (-9100 7400) $PN 2
J 0
(-9090 7410);
DISPLAY 0.680851 (-9090 7410);
PAINT MONO (-9090 7410);
FORCEPROP 1 LAST VALUE 330OHM
J 0
(-9100 7450);
DISPLAY 1.212766 (-9100 7450);
PAINT GREEN (-9100 7450);
FORCEPROP 0 LAST PACKAGE 0402
J 0
(-9300 7300);
DISPLAY 1.021277 (-9300 7300);
FORCEPROP 1 LAST PATH I192
J 0
(-9447 7505);
DISPLAY 1.212766 (-9447 7505);
PAINT GREEN (-9447 7505);
DISPLAY INVISIBLE (-9447 7505);
FORCEPROP 1 LAST TOLERANCE 1%
J 0
(-9447 7655);
DISPLAY 1.212766 (-9447 7655);
PAINT GREEN (-9447 7655);
DISPLAY INVISIBLE (-9447 7655);
FORCEPROP 2 LAST CDS_LIB passive
J 0
(-9250 7400);
DISPLAY INVISIBLE (-9250 7400);
FORCEPROP 1 LAST CDS_LMAN_SYM_OUTLINE -50,50,100,-50
J 0
(-9250 7400);
DISPLAY 0.468085 (-9250 7400);
PAINT GREEN (-9250 7400);
DISPLAY INVISIBLE (-9250 7400);
FORCEPROP 1 LAST CLS_PN G155-13300-01
J 0
(-9386 7600);
DISPLAY 1.212766 (-9386 7600);
PAINT GREEN (-9386 7600);
DISPLAY INVISIBLE (-9386 7600);
FORCEADD OPTICAL..1
R 2
(-10600 7400);
FORCEPROP 1 LAST $LOCATION DS20
J 0
(-10412 7450);
DISPLAY 1.212766 (-10412 7450);
PAINT GREEN (-10412 7450);
FORCEPROP 0 LAST CDS_LOCATION DS20
J 0
(-11550 7600);
DISPLAY 1.021277 (-11550 7600);
DISPLAY INVISIBLE (-11550 7600);
FORCEPROP 0 LAST $SEC 1
J 0
(-11550 7600);
DISPLAY 0.680851 (-11550 7600);
PAINT MONO (-11550 7600);
DISPLAY INVISIBLE (-11550 7600);
FORCEPROP 0 LAST CDS_SEC 1
J 0
(-11550 7600);
DISPLAY 1.021277 (-11550 7600);
DISPLAY INVISIBLE (-11550 7600);
FORCEPROP 0 LASTPIN (-10350 7400) $PN A
J 0
(-10340 7410);
DISPLAY 0.680851 (-10340 7410);
PAINT MONO (-10340 7410);
FORCEPROP 0 LASTPIN (-10850 7400) $PN C
J 2
(-10860 7410);
DISPLAY 0.680851 (-10860 7410);
PAINT MONO (-10860 7410);
FORCEPROP 1 LAST CLS_PN G170-10143-01
J 2
(-10800 7450);
DISPLAY 1.212766 (-10800 7450);
PAINT GREEN (-10800 7450);
FORCEPROP 0 LAST PART_NUMBER LTST-C190KGKT
J 0
(-11550 7550);
DISPLAY 1.021277 (-11550 7550);
FORCEPROP 1 LAST PATH I194
J 2
(-10700 7600);
DISPLAY 1.212766 (-10700 7600);
PAINT GREEN (-10700 7600);
DISPLAY INVISIBLE (-10700 7600);
FORCEPROP 2 LASTPIN (-10350 7400) SIG_NAME UN$14$OPTICAL$I194$A
J 0
(-10340 7410);
DISPLAY 0.659574 (-10340 7410);
PAINT MONO (-10340 7410);
DISPLAY INVISIBLE (-10340 7410);
FORCEPROP 2 LAST CDS_LIB discrete
J 0
(-10600 7400);
DISPLAY INVISIBLE (-10600 7400);
FORCEPROP 1 LAST CDS_LMAN_SYM_OUTLINE -150,100,150,-50
J 2
(-10600 7400);
DISPLAY 0.468085 (-10600 7400);
PAINT GREEN (-10600 7400);
DISPLAY INVISIBLE (-10600 7400);
FORCEADD VCC..1
(-7850 7500);
FORCEPROP 3 LASTPIN (-7800 7450) SIG_NAME XP3R3V_AUX_PCIE\g
J 0
(-7790 7460);
DISPLAY 0.659574 (-7790 7460);
PAINT MONO (-7790 7460);
DISPLAY INVISIBLE (-7790 7460);
FORCEPROP 1 LAST HDL_POWER XP3R3V_AUX_PCIE
J 1
(-7800 7550);
DISPLAY 0.808511 (-7800 7550);
PAINT GREEN (-7800 7550);
FORCEPROP 0 LAST VOLTAGE 3.3
J 1
(-7800 7600);
DISPLAY 1.021277 (-7800 7600);
DISPLAY BOTH (-7800 7600);
FORCEPROP 1 LAST PATH I195
J 0
(-7815 7590);
DISPLAY 0.808511 (-7815 7590);
PAINT GREEN (-7815 7590);
DISPLAY INVISIBLE (-7815 7590);
FORCEPROP 1 LAST BODY_TYPE PLUMBING
J 0
(-7895 7457);
DISPLAY 0.340426 (-7895 7457);
PAINT GREEN (-7895 7457);
DISPLAY INVISIBLE (-7895 7457);
FORCEPROP 2 LAST CDS_LIB cls
J 0
(-7850 7500);
DISPLAY INVISIBLE (-7850 7500);
FORCEPROP 1 LAST CDS_LMAN_SYM_OUTLINE -250,250,250,-250
J 0
(-7850 7500);
DISPLAY 0.468085 (-7850 7500);
PAINT GREEN (-7850 7500);
DISPLAY INVISIBLE (-7850 7500);
FORCEADD VCC..1
(-7850 7850);
FORCEPROP 3 LASTPIN (-7800 7800) SIG_NAME XP3R3V_PCIE\g
J 0
(-7790 7810);
DISPLAY 0.659574 (-7790 7810);
PAINT MONO (-7790 7810);
DISPLAY INVISIBLE (-7790 7810);
FORCEPROP 1 LAST HDL_POWER XP3R3V_PCIE
J 1
(-7800 7900);
DISPLAY 0.808511 (-7800 7900);
PAINT GREEN (-7800 7900);
FORCEPROP 0 LAST VOLTAGE 3.3
J 1
(-7800 7950);
DISPLAY 1.021277 (-7800 7950);
DISPLAY BOTH (-7800 7950);
FORCEPROP 1 LAST PATH I196
J 0
(-7815 7940);
DISPLAY 0.808511 (-7815 7940);
PAINT GREEN (-7815 7940);
DISPLAY INVISIBLE (-7815 7940);
FORCEPROP 1 LAST BODY_TYPE PLUMBING
J 0
(-7895 7807);
DISPLAY 0.340426 (-7895 7807);
PAINT GREEN (-7895 7807);
DISPLAY INVISIBLE (-7895 7807);
FORCEPROP 2 LAST CDS_LIB cls
J 0
(-7850 7850);
DISPLAY INVISIBLE (-7850 7850);
FORCEPROP 1 LAST CDS_LMAN_SYM_OUTLINE -250,250,250,-250
J 0
(-7850 7850);
DISPLAY 0.468085 (-7850 7850);
PAINT GREEN (-7850 7850);
DISPLAY INVISIBLE (-7850 7850);
FORCEADD IS32FL3207_QWLA3_TR_QFN29..1
(-9200 5700);
FORCEPROP 1 LAST $LOCATION U33
J 0
(-9150 5800);
DISPLAY 1.212766 (-9150 5800);
PAINT GREEN (-9150 5800);
FORCEPROP 0 LAST CDS_LOCATION U33
J 0
(-9150 6100);
DISPLAY 1.021277 (-9150 6100);
DISPLAY INVISIBLE (-9150 6100);
FORCEPROP 0 LAST $SEC 1
J 0
(-9150 6100);
DISPLAY 0.680851 (-9150 6100);
PAINT MONO (-9150 6100);
DISPLAY INVISIBLE (-9150 6100);
FORCEPROP 0 LAST CDS_SEC 1
J 0
(-9150 6100);
DISPLAY 1.021277 (-9150 6100);
DISPLAY INVISIBLE (-9150 6100);
FORCEPROP 0 LASTPIN (-9300 4000) $PN 2
J 2
(-9310 4010);
DISPLAY 0.680851 (-9310 4010);
PAINT MONO (-9310 4010);
FORCEPROP 0 LASTPIN (-8350 3700) $PN 4
J 0
(-8340 3710);
DISPLAY 0.680851 (-8340 3710);
PAINT MONO (-8340 3710);
FORCEPROP 0 LASTPIN (-8350 3600) $PN 11
J 0
(-8340 3610);
DISPLAY 0.680851 (-8340 3610);
PAINT MONO (-8340 3610);
FORCEPROP 0 LASTPIN (-8350 3500) $PN 18
J 0
(-8340 3510);
DISPLAY 0.680851 (-8340 3510);
PAINT MONO (-8340 3510);
FORCEPROP 0 LASTPIN (-8350 3400) $PN 25
J 0
(-8340 3410);
DISPLAY 0.680851 (-8340 3410);
PAINT MONO (-8340 3410);
FORCEPROP 0 LASTPIN (-9300 4200) $PN 5
J 2
(-9310 4210);
DISPLAY 0.680851 (-9310 4210);
PAINT MONO (-9310 4210);
FORCEPROP 0 LASTPIN (-8350 5600) $PN 8
J 0
(-8340 5610);
DISPLAY 0.680851 (-8340 5610);
PAINT MONO (-8340 5610);
FORCEPROP 0 LASTPIN (-8350 5500) $PN 9
J 0
(-8340 5510);
DISPLAY 0.680851 (-8340 5510);
PAINT MONO (-8340 5510);
FORCEPROP 0 LASTPIN (-8350 5400) $PN 10
J 0
(-8340 5410);
DISPLAY 0.680851 (-8340 5410);
PAINT MONO (-8340 5410);
FORCEPROP 0 LASTPIN (-8350 5300) $PN 12
J 0
(-8340 5310);
DISPLAY 0.680851 (-8340 5310);
PAINT MONO (-8340 5310);
FORCEPROP 0 LASTPIN (-8350 5200) $PN 13
J 0
(-8340 5210);
DISPLAY 0.680851 (-8340 5210);
PAINT MONO (-8340 5210);
FORCEPROP 0 LASTPIN (-8350 5100) $PN 14
J 0
(-8340 5110);
DISPLAY 0.680851 (-8340 5110);
PAINT MONO (-8340 5110);
FORCEPROP 0 LASTPIN (-8350 5000) $PN 15
J 0
(-8340 5010);
DISPLAY 0.680851 (-8340 5010);
PAINT MONO (-8340 5010);
FORCEPROP 0 LASTPIN (-8350 4900) $PN 16
J 0
(-8340 4910);
DISPLAY 0.680851 (-8340 4910);
PAINT MONO (-8340 4910);
FORCEPROP 0 LASTPIN (-8350 4800) $PN 17
J 0
(-8340 4810);
DISPLAY 0.680851 (-8340 4810);
PAINT MONO (-8340 4810);
FORCEPROP 0 LASTPIN (-8350 4700) $PN 19
J 0
(-8340 4710);
DISPLAY 0.680851 (-8340 4710);
PAINT MONO (-8340 4710);
FORCEPROP 0 LASTPIN (-8350 4600) $PN 20
J 0
(-8340 4610);
DISPLAY 0.680851 (-8340 4610);
PAINT MONO (-8340 4610);
FORCEPROP 0 LASTPIN (-8350 4500) $PN 21
J 0
(-8340 4510);
DISPLAY 0.680851 (-8340 4510);
PAINT MONO (-8340 4510);
FORCEPROP 0 LASTPIN (-8350 4400) $PN 22
J 0
(-8340 4410);
DISPLAY 0.680851 (-8340 4410);
PAINT MONO (-8340 4410);
FORCEPROP 0 LASTPIN (-8350 4300) $PN 23
J 0
(-8340 4310);
DISPLAY 0.680851 (-8340 4310);
PAINT MONO (-8340 4310);
FORCEPROP 0 LASTPIN (-8350 4200) $PN 24
J 0
(-8340 4210);
DISPLAY 0.680851 (-8340 4210);
PAINT MONO (-8340 4210);
FORCEPROP 0 LASTPIN (-8350 4100) $PN 26
J 0
(-8340 4110);
DISPLAY 0.680851 (-8340 4110);
PAINT MONO (-8340 4110);
FORCEPROP 0 LASTPIN (-8350 4000) $PN 27
J 0
(-8340 4010);
DISPLAY 0.680851 (-8340 4010);
PAINT MONO (-8340 4010);
FORCEPROP 0 LASTPIN (-8350 3900) $PN 28
J 0
(-8340 3910);
DISPLAY 0.680851 (-8340 3910);
PAINT MONO (-8340 3910);
FORCEPROP 0 LASTPIN (-9300 5000) $PN 7
J 2
(-9310 5010);
DISPLAY 0.680851 (-9310 5010);
PAINT MONO (-9310 5010);
FORCEPROP 0 LASTPIN (-9300 5100) $PN 6
J 2
(-9310 5110);
DISPLAY 0.680851 (-9310 5110);
PAINT MONO (-9310 5110);
FORCEPROP 0 LASTPIN (-9300 4800) $PN 1
J 2
(-9310 4810);
DISPLAY 0.680851 (-9310 4810);
PAINT MONO (-9310 4810);
FORCEPROP 0 LASTPIN (-8350 3200) $PN 29
J 0
(-8340 3210);
DISPLAY 0.680851 (-8340 3210);
PAINT MONO (-8340 3210);
FORCEPROP 0 LASTPIN (-9300 5600) $PN 3
J 2
(-9310 5610);
DISPLAY 0.680851 (-9310 5610);
PAINT MONO (-9310 5610);
FORCEPROP 1 LAST CLS_PN A223-00002-FB
J 0
(-9150 5900);
DISPLAY 1.212766 (-9150 5900);
PAINT GREEN (-9150 5900);
FORCEPROP 1 LAST VALUE IS32FL3207-QWLA3-TR
J 0
(-9150 6000);
DISPLAY 1.212766 (-9150 6000);
PAINT GREEN (-9150 6000);
FORCEPROP 2 LASTPIN (-9300 4000) SIG_NAME UN$14$IS32FL3207QWLA3TRQFN29$I219$AD
J 0
(-9290 4010);
DISPLAY 0.659574 (-9290 4010);
PAINT MONO (-9290 4010);
DISPLAY INVISIBLE (-9290 4010);
FORCEPROP 2 LASTPIN (-9300 4200) SIG_NAME UN$14$IS32FL3207QWLA3TRQFN29$I219$ISET
J 0
(-9290 4210);
DISPLAY 0.659574 (-9290 4210);
PAINT MONO (-9290 4210);
DISPLAY INVISIBLE (-9290 4210);
FORCEPROP 1 LAST CDS_LMAN_SYM_OUTLINE 0,0,750,-2600
J 0
(-9200 5700);
DISPLAY 0.468085 (-9200 5700);
PAINT GREEN (-9200 5700);
DISPLAY INVISIBLE (-9200 5700);
FORCEPROP 2 LAST CDS_LIB interface
J 0
(-9200 5700);
DISPLAY INVISIBLE (-9200 5700);
FORCEPROP 1 LAST PATH I219
J 0
(-9150 5750);
DISPLAY 1.212766 (-9150 5750);
PAINT GREEN (-9150 5750);
DISPLAY INVISIBLE (-9150 5750);
FORCEADD OFFPAGE_OUT..1
R 6
(-6700 4400);
FORCEPROP 2 LAST $XR0 26K12> 
J 0
(-6645 4400);
DISPLAY 0.638298 (-6645 4400);
PAINT MONO (-6645 4400);
FORCEPROP 2 LAST CDS_LIB cls
J 0
(-6700 4400);
DISPLAY INVISIBLE (-6700 4400);
FORCEPROP 1 LAST CDS_LMAN_SYM_OUTLINE -50,50,50,-50
J 0
(-6700 4400);
DISPLAY 0.468085 (-6700 4400);
PAINT GREEN (-6700 4400);
DISPLAY INVISIBLE (-6700 4400);
FORCEPROP 1 LAST BODY_TYPE COMMENT
J 0
(-6690 4227);
DISPLAY 0.808511 (-6690 4227);
PAINT GREEN (-6690 4227);
DISPLAY INVISIBLE (-6690 4227);
FORCEPROP 1 LAST OFFPAGE TRUE
J 0
(-6690 4307);
DISPLAY 0.808511 (-6690 4307);
PAINT GREEN (-6690 4307);
DISPLAY INVISIBLE (-6690 4307);
FORCEPROP 2 LAST PATH I232
J 0
(-6650 4500);
DISPLAY 1.021277 (-6650 4500);
DISPLAY INVISIBLE (-6650 4500);
FORCEADD OFFPAGE_OUT..1
R 6
(-6700 4300);
FORCEPROP 2 LAST $XR0 26K12> 
J 0
(-6645 4300);
DISPLAY 0.638298 (-6645 4300);
PAINT MONO (-6645 4300);
FORCEPROP 2 LAST CDS_LIB cls
J 0
(-6700 4300);
DISPLAY INVISIBLE (-6700 4300);
FORCEPROP 1 LAST CDS_LMAN_SYM_OUTLINE -50,50,50,-50
J 0
(-6700 4300);
DISPLAY 0.468085 (-6700 4300);
PAINT GREEN (-6700 4300);
DISPLAY INVISIBLE (-6700 4300);
FORCEPROP 1 LAST BODY_TYPE COMMENT
J 0
(-6690 4127);
DISPLAY 0.808511 (-6690 4127);
PAINT GREEN (-6690 4127);
DISPLAY INVISIBLE (-6690 4127);
FORCEPROP 1 LAST OFFPAGE TRUE
J 0
(-6690 4207);
DISPLAY 0.808511 (-6690 4207);
PAINT GREEN (-6690 4207);
DISPLAY INVISIBLE (-6690 4207);
FORCEPROP 2 LAST PATH I233
J 0
(-6650 4400);
DISPLAY 1.021277 (-6650 4400);
DISPLAY INVISIBLE (-6650 4400);
FORCEADD OFFPAGE_OUT..1
R 6
(-6700 4200);
FORCEPROP 2 LAST $XR0 26K12> 
J 0
(-6645 4200);
DISPLAY 0.638298 (-6645 4200);
PAINT MONO (-6645 4200);
FORCEPROP 2 LAST CDS_LIB cls
J 0
(-6700 4200);
DISPLAY INVISIBLE (-6700 4200);
FORCEPROP 1 LAST CDS_LMAN_SYM_OUTLINE -50,50,50,-50
J 0
(-6700 4200);
DISPLAY 0.468085 (-6700 4200);
PAINT GREEN (-6700 4200);
DISPLAY INVISIBLE (-6700 4200);
FORCEPROP 1 LAST BODY_TYPE COMMENT
J 0
(-6690 4027);
DISPLAY 0.808511 (-6690 4027);
PAINT GREEN (-6690 4027);
DISPLAY INVISIBLE (-6690 4027);
FORCEPROP 1 LAST OFFPAGE TRUE
J 0
(-6690 4107);
DISPLAY 0.808511 (-6690 4107);
PAINT GREEN (-6690 4107);
DISPLAY INVISIBLE (-6690 4107);
FORCEPROP 2 LAST PATH I234
J 0
(-6650 4300);
DISPLAY 1.021277 (-6650 4300);
DISPLAY INVISIBLE (-6650 4300);
FORCEADD GND_SG..1
(-8200 3050);
FORCEPROP 3 LASTPIN (-8150 3100) SIG_NAME SG\g
J 0
(-8140 3110);
DISPLAY 0.659574 (-8140 3110);
PAINT MONO (-8140 3110);
DISPLAY INVISIBLE (-8140 3110);
FORCEPROP 1 LAST HDL_POWER SG
J 1
(-8145 2955);
DISPLAY 0.808511 (-8145 2955);
PAINT GREEN (-8145 2955);
FORCEPROP 1 LAST CDS_LMAN_SYM_OUTLINE 0,0,100,-50
J 0
(-8200 3050);
DISPLAY 0.468085 (-8200 3050);
PAINT GREEN (-8200 3050);
DISPLAY INVISIBLE (-8200 3050);
FORCEPROP 2 LAST CDS_LIB cls
J 0
(-8200 3050);
DISPLAY INVISIBLE (-8200 3050);
FORCEPROP 1 LAST BODY_TYPE PLUMBING
J 0
(-8185 3035);
DISPLAY 0.808511 (-8185 3035);
PAINT GREEN (-8185 3035);
DISPLAY INVISIBLE (-8185 3035);
FORCEPROP 1 LAST PATH I235
J 0
(-8165 3050);
DISPLAY 0.808511 (-8165 3050);
PAINT GREEN (-8165 3050);
DISPLAY INVISIBLE (-8165 3050);
FORCEADD VCC..1
(-11750 6300);
FORCEPROP 3 LASTPIN (-11700 6250) SIG_NAME XP3R3V_FPGA\g
J 0
(-11690 6260);
DISPLAY 0.659574 (-11690 6260);
PAINT MONO (-11690 6260);
DISPLAY INVISIBLE (-11690 6260);
FORCEPROP 0 LAST VOLTAGE 3.3V
J 0
(-12000 6450);
DISPLAY 1.021277 (-12000 6450);
DISPLAY BOTH (-12000 6450);
FORCEPROP 1 LAST HDL_POWER XP3R3V_FPGA
J 1
(-11695 6355);
DISPLAY 1.021277 (-11695 6355);
PAINT GREEN (-11695 6355);
FORCEPROP 2 LAST CDS_LIB cls
J 0
(-11750 6300);
DISPLAY INVISIBLE (-11750 6300);
FORCEPROP 1 LAST CDS_LMAN_SYM_OUTLINE -250,250,250,-250
J 0
(-11750 6300);
DISPLAY 0.468085 (-11750 6300);
PAINT GREEN (-11750 6300);
DISPLAY INVISIBLE (-11750 6300);
FORCEPROP 1 LAST BODY_TYPE PLUMBING
J 0
(-11795 6257);
DISPLAY 0.340426 (-11795 6257);
PAINT GREEN (-11795 6257);
DISPLAY INVISIBLE (-11795 6257);
FORCEPROP 1 LAST PATH I236
J 0
(-11715 6390);
DISPLAY 0.808511 (-11715 6390);
PAINT GREEN (-11715 6390);
DISPLAY INVISIBLE (-11715 6390);
FORCEADD CAPACITOR..2
R 2
(-10150 5900);
FORCEPROP 1 LAST $LOCATION C315
J 2
(-9900 5750);
DISPLAY 1.212766 (-9900 5750);
PAINT GREEN (-9900 5750);
FORCEPROP 0 LAST CDS_LOCATION C315
J 0
(-10000 6000);
DISPLAY 1.021277 (-10000 6000);
DISPLAY INVISIBLE (-10000 6000);
FORCEPROP 0 LAST $SEC 1
J 0
(-10000 6000);
DISPLAY 0.680851 (-10000 6000);
PAINT MONO (-10000 6000);
DISPLAY INVISIBLE (-10000 6000);
FORCEPROP 0 LAST CDS_SEC 1
J 0
(-10000 6000);
DISPLAY 1.021277 (-10000 6000);
DISPLAY INVISIBLE (-10000 6000);
FORCEPROP 0 LASTPIN (-10150 6000) $PN 1
R 1
J 0
(-10160 6010);
DISPLAY 0.680851 (-10160 6010);
PAINT MONO (-10160 6010);
FORCEPROP 0 LASTPIN (-10150 5750) $PN 2
R 1
J 2
(-10160 5740);
DISPLAY 0.680851 (-10160 5740);
PAINT MONO (-10160 5740);
FORCEPROP 1 LAST VALUE 0.1UF
J 2
(-9750 5850);
DISPLAY 1.212766 (-9750 5850);
PAINT GREEN (-9750 5850);
FORCEPROP 0 LAST VOLTAGE 25V
J 0
(-10000 6050);
DISPLAY 1.021277 (-10000 6050);
FORCEPROP 0 LAST PACKAGE 0402
J 0
(-10000 5950);
DISPLAY 1.021277 (-10000 5950);
FORCEPROP 1 LAST CLS_PN G105-0B104-EK
J 2
(-10050 5950);
DISPLAY 1.212766 (-10050 5950);
PAINT GREEN (-10050 5950);
DISPLAY INVISIBLE (-10050 5950);
FORCEPROP 1 LAST TOLERANCE 10%
J 2
(-10000 6000);
DISPLAY 1.212766 (-10000 6000);
PAINT GREEN (-10000 6000);
DISPLAY INVISIBLE (-10000 6000);
FORCEPROP 1 LAST CDS_LMAN_SYM_OUTLINE -50,0,50,-50
J 2
(-10150 5900);
DISPLAY 0.468085 (-10150 5900);
PAINT GREEN (-10150 5900);
DISPLAY INVISIBLE (-10150 5900);
FORCEPROP 2 LAST CDS_LIB passive
J 0
(-10150 5900);
DISPLAY INVISIBLE (-10150 5900);
FORCEPROP 1 LAST PATH I237
J 2
(-10050 5950);
DISPLAY 1.212766 (-10050 5950);
PAINT GREEN (-10050 5950);
DISPLAY INVISIBLE (-10050 5950);
FORCEADD CAPACITOR..2
R 2
(-10550 5900);
FORCEPROP 1 LAST $LOCATION C314
J 2
(-10300 5750);
DISPLAY 1.212766 (-10300 5750);
PAINT GREEN (-10300 5750);
FORCEPROP 0 LAST CDS_LOCATION C314
J 0
(-10450 6000);
DISPLAY 1.021277 (-10450 6000);
DISPLAY INVISIBLE (-10450 6000);
FORCEPROP 0 LAST $SEC 1
J 0
(-10450 6000);
DISPLAY 0.680851 (-10450 6000);
PAINT MONO (-10450 6000);
DISPLAY INVISIBLE (-10450 6000);
FORCEPROP 0 LAST CDS_SEC 1
J 0
(-10450 6000);
DISPLAY 1.021277 (-10450 6000);
DISPLAY INVISIBLE (-10450 6000);
FORCEPROP 0 LASTPIN (-10550 6000) $PN 1
R 1
J 0
(-10560 6010);
DISPLAY 0.680851 (-10560 6010);
PAINT MONO (-10560 6010);
FORCEPROP 0 LASTPIN (-10550 5750) $PN 2
R 1
J 2
(-10560 5740);
DISPLAY 0.680851 (-10560 5740);
PAINT MONO (-10560 5740);
FORCEPROP 1 LAST VALUE 10UF
J 2
(-10250 5850);
DISPLAY 1.212766 (-10250 5850);
PAINT GREEN (-10250 5850);
FORCEPROP 0 LAST PACKAGE 0402
J 0
(-10450 5950);
DISPLAY 1.021277 (-10450 5950);
FORCEPROP 0 LAST VOLTAGE 6.3V
J 0
(-10450 6050);
DISPLAY 1.021277 (-10450 6050);
FORCEPROP 1 LAST PATH I238
J 2
(-10450 5950);
DISPLAY 1.212766 (-10450 5950);
PAINT GREEN (-10450 5950);
DISPLAY INVISIBLE (-10450 5950);
FORCEPROP 1 LAST CLS_PN G105-0C106-BM
J 2
(-10450 5950);
DISPLAY 1.212766 (-10450 5950);
PAINT GREEN (-10450 5950);
DISPLAY INVISIBLE (-10450 5950);
FORCEPROP 1 LAST TOLERANCE 20%
J 2
(-10400 6000);
DISPLAY 1.212766 (-10400 6000);
PAINT GREEN (-10400 6000);
DISPLAY INVISIBLE (-10400 6000);
FORCEPROP 1 LAST CDS_LMAN_SYM_OUTLINE -50,0,50,-50
J 2
(-10550 5900);
DISPLAY 0.468085 (-10550 5900);
PAINT GREEN (-10550 5900);
DISPLAY INVISIBLE (-10550 5900);
FORCEPROP 2 LAST CDS_LIB passive
J 0
(-10550 5900);
DISPLAY INVISIBLE (-10550 5900);
FORCEADD GND_SG..1
(-10200 5550);
FORCEPROP 3 LASTPIN (-10150 5600) SIG_NAME SG\g
J 0
(-10140 5610);
DISPLAY 0.659574 (-10140 5610);
PAINT MONO (-10140 5610);
DISPLAY INVISIBLE (-10140 5610);
FORCEPROP 1 LAST HDL_POWER SG
J 1
(-10145 5455);
DISPLAY 0.808511 (-10145 5455);
PAINT GREEN (-10145 5455);
FORCEPROP 1 LAST CDS_LMAN_SYM_OUTLINE 0,0,100,-50
J 0
(-10200 5550);
DISPLAY 0.468085 (-10200 5550);
PAINT GREEN (-10200 5550);
DISPLAY INVISIBLE (-10200 5550);
FORCEPROP 2 LAST CDS_LIB cls
J 0
(-10200 5550);
DISPLAY INVISIBLE (-10200 5550);
FORCEPROP 1 LAST BODY_TYPE PLUMBING
J 0
(-10185 5535);
DISPLAY 0.808511 (-10185 5535);
PAINT GREEN (-10185 5535);
DISPLAY INVISIBLE (-10185 5535);
FORCEPROP 1 LAST PATH I239
J 0
(-10165 5550);
DISPLAY 0.808511 (-10165 5550);
PAINT GREEN (-10165 5550);
DISPLAY INVISIBLE (-10165 5550);
FORCEADD RESISTOR..2
(-10050 3750);
FORCEPROP 1 LAST $LOCATION R323
J 0
(-10000 3600);
DISPLAY 1.212766 (-10000 3600);
PAINT GREEN (-10000 3600);
FORCEPROP 0 LAST CDS_LOCATION R323
J 0
(-10000 3850);
DISPLAY 1.021277 (-10000 3850);
DISPLAY INVISIBLE (-10000 3850);
FORCEPROP 0 LAST $SEC 1
J 0
(-10000 3850);
DISPLAY 0.680851 (-10000 3850);
PAINT MONO (-10000 3850);
DISPLAY INVISIBLE (-10000 3850);
FORCEPROP 0 LAST CDS_SEC 1
J 0
(-10000 3850);
DISPLAY 1.021277 (-10000 3850);
DISPLAY INVISIBLE (-10000 3850);
FORCEPROP 0 LASTPIN (-10050 3850) $PN 1
R 1
J 0
(-10060 3860);
DISPLAY 0.680851 (-10060 3860);
PAINT MONO (-10060 3860);
FORCEPROP 0 LASTPIN (-10050 3600) $PN 2
R 1
J 2
(-10060 3590);
DISPLAY 0.680851 (-10060 3590);
PAINT MONO (-10060 3590);
FORCEPROP 1 LAST VALUE 4.7KOHM
J 0
(-10000 3700);
DISPLAY 0.978723 (-10000 3700);
PAINT GREEN (-10000 3700);
FORCEPROP 0 LAST PACKAGE 0402
J 0
(-10000 3800);
DISPLAY 1.021277 (-10000 3800);
FORCEPROP 2 LAST CDS_LIB passive
J 0
(-10050 3750);
DISPLAY INVISIBLE (-10050 3750);
FORCEPROP 1 LAST CDS_LMAN_SYM_OUTLINE -50,50,50,-100
J 0
(-10050 3750);
DISPLAY 0.468085 (-10050 3750);
PAINT GREEN (-10050 3750);
DISPLAY INVISIBLE (-10050 3750);
FORCEPROP 1 LAST CLS_PN G155-14701-01
J 0
(-10186 3950);
DISPLAY 1.212766 (-10186 3950);
PAINT GREEN (-10186 3950);
DISPLAY INVISIBLE (-10186 3950);
FORCEPROP 1 LAST TOLERANCE 1%
J 0
(-10247 4005);
DISPLAY 1.212766 (-10247 4005);
PAINT GREEN (-10247 4005);
DISPLAY INVISIBLE (-10247 4005);
FORCEPROP 1 LAST PATH I246
J 0
(-10247 3855);
DISPLAY 1.212766 (-10247 3855);
PAINT GREEN (-10247 3855);
DISPLAY INVISIBLE (-10247 3855);
FORCEADD RESISTOR..1
R 1
(-9600 3700);
FORCEPROP 1 LAST $LOCATION R324
J 2
(-9400 3600);
DISPLAY 1.212766 (-9400 3600);
PAINT GREEN (-9400 3600);
FORCEPROP 0 LAST CDS_LOCATION R324
R 1
J 0
(-9500 3850);
DISPLAY 1.021277 (-9500 3850);
DISPLAY INVISIBLE (-9500 3850);
FORCEPROP 0 LAST $SEC 1
R 1
J 0
(-9500 3850);
DISPLAY 0.680851 (-9500 3850);
PAINT MONO (-9500 3850);
DISPLAY INVISIBLE (-9500 3850);
FORCEPROP 0 LAST CDS_SEC 1
R 1
J 0
(-9500 3850);
DISPLAY 1.021277 (-9500 3850);
DISPLAY INVISIBLE (-9500 3850);
FORCEPROP 0 LASTPIN (-9600 3600) $PN 1
R 1
J 2
(-9610 3590);
DISPLAY 0.680851 (-9610 3590);
PAINT MONO (-9610 3590);
FORCEPROP 0 LASTPIN (-9600 3850) $PN 2
R 1
J 0
(-9610 3860);
DISPLAY 0.680851 (-9610 3860);
PAINT MONO (-9610 3860);
FORCEPROP 0 LAST PACKAGE 0402
J 0
(-9500 3800);
DISPLAY 1.021277 (-9500 3800);
FORCEPROP 1 LAST VALUE 0OHM
J 0
(-9500 3700);
DISPLAY 1.212766 (-9500 3700);
PAINT GREEN (-9500 3700);
FORCEPROP 1 LAST CLS_PN G155-100R0-J0
R 1
J 0
(-9800 3564);
DISPLAY 1.212766 (-9800 3564);
PAINT GREEN (-9800 3564);
DISPLAY INVISIBLE (-9800 3564);
FORCEPROP 1 LAST CDS_LMAN_SYM_OUTLINE -50,50,100,-50
R 1
J 0
(-9600 3700);
DISPLAY 0.468085 (-9600 3700);
PAINT GREEN (-9600 3700);
DISPLAY INVISIBLE (-9600 3700);
FORCEPROP 2 LAST CDS_LIB passive
R 1
J 0
(-9600 3700);
DISPLAY INVISIBLE (-9600 3700);
FORCEPROP 1 LAST TOLERANCE -
R 1
J 0
(-9855 3503);
DISPLAY 1.212766 (-9855 3503);
PAINT GREEN (-9855 3503);
DISPLAY INVISIBLE (-9855 3503);
FORCEPROP 1 LAST PATH I247
R 1
J 0
(-9705 3503);
DISPLAY 1.212766 (-9705 3503);
PAINT GREEN (-9705 3503);
DISPLAY INVISIBLE (-9705 3503);
FORCEADD GND_SG..1
(-10100 3350);
FORCEPROP 3 LASTPIN (-10050 3400) SIG_NAME SG\g
J 0
(-10040 3410);
DISPLAY 0.659574 (-10040 3410);
PAINT MONO (-10040 3410);
DISPLAY INVISIBLE (-10040 3410);
FORCEPROP 1 LAST HDL_POWER SG
J 1
(-10045 3255);
DISPLAY 0.808511 (-10045 3255);
PAINT GREEN (-10045 3255);
FORCEPROP 1 LAST CDS_LMAN_SYM_OUTLINE 0,0,100,-50
J 0
(-10100 3350);
DISPLAY 0.468085 (-10100 3350);
PAINT GREEN (-10100 3350);
DISPLAY INVISIBLE (-10100 3350);
FORCEPROP 2 LAST CDS_LIB cls
J 0
(-10100 3350);
DISPLAY INVISIBLE (-10100 3350);
FORCEPROP 1 LAST BODY_TYPE PLUMBING
J 0
(-10085 3335);
DISPLAY 0.808511 (-10085 3335);
PAINT GREEN (-10085 3335);
DISPLAY INVISIBLE (-10085 3335);
FORCEPROP 1 LAST PATH I248
J 0
(-10065 3350);
DISPLAY 0.808511 (-10065 3350);
PAINT GREEN (-10065 3350);
DISPLAY INVISIBLE (-10065 3350);
FORCEADD RESISTOR..1
(-11900 4800);
FORCEPROP 1 LAST $LOCATION R319
J 2
(-12100 4800);
DISPLAY 1.212766 (-12100 4800);
PAINT GREEN (-12100 4800);
FORCEPROP 0 LAST CDS_LOCATION R319
J 0
(-11700 4900);
DISPLAY 1.021277 (-11700 4900);
DISPLAY INVISIBLE (-11700 4900);
FORCEPROP 0 LAST $SEC 1
J 0
(-11700 4900);
DISPLAY 0.680851 (-11700 4900);
PAINT MONO (-11700 4900);
DISPLAY INVISIBLE (-11700 4900);
FORCEPROP 0 LAST CDS_SEC 1
J 0
(-11700 4900);
DISPLAY 1.021277 (-11700 4900);
DISPLAY INVISIBLE (-11700 4900);
FORCEPROP 0 LASTPIN (-12000 4800) $PN 1
J 2
(-12010 4810);
DISPLAY 0.680851 (-12010 4810);
PAINT MONO (-12010 4810);
FORCEPROP 0 LASTPIN (-11750 4800) $PN 2
J 0
(-11740 4810);
DISPLAY 0.680851 (-11740 4810);
PAINT MONO (-11740 4810);
FORCEPROP 0 LAST PACKAGE 0402
J 0
(-11950 4850);
DISPLAY 0.638298 (-11950 4850);
FORCEPROP 1 LAST VALUE 33OHM
J 0
(-11700 4800);
DISPLAY 0.978723 (-11700 4800);
PAINT GREEN (-11700 4800);
FORCEPROP 0 LAST NO_ASSY TRUE
J 0
(-11950 4750);
DISPLAY 0.638298 (-11950 4750);
DISPLAY BOTH (-11950 4750);
FORCEPROP 1 LAST PATH I249
J 0
(-12097 4905);
DISPLAY 1.212766 (-12097 4905);
PAINT GREEN (-12097 4905);
DISPLAY INVISIBLE (-12097 4905);
FORCEPROP 1 LAST TOLERANCE 1%
J 0
(-12097 5055);
DISPLAY 1.212766 (-12097 5055);
PAINT GREEN (-12097 5055);
DISPLAY INVISIBLE (-12097 5055);
FORCEPROP 1 LAST CLS_PN G155-133R0-01
J 0
(-12036 5000);
DISPLAY 1.212766 (-12036 5000);
PAINT GREEN (-12036 5000);
DISPLAY INVISIBLE (-12036 5000);
FORCEPROP 2 LAST SIGNAL_MODEL DEFAULT_RESISTOR_33OHM_2_1
J 0
(-12050 5000);
DISPLAY 1.021277 (-12050 5000);
DISPLAY INVISIBLE (-12050 5000);
FORCEPROP 1 LAST CDS_LMAN_SYM_OUTLINE -50,50,100,-50
J 0
(-11900 4800);
DISPLAY 0.468085 (-11900 4800);
PAINT GREEN (-11900 4800);
DISPLAY INVISIBLE (-11900 4800);
FORCEPROP 2 LAST CDS_LIB passive
J 0
(-11900 4800);
DISPLAY INVISIBLE (-11900 4800);
FORCEADD CAPACITOR..2
R 2
(-9750 4600);
FORCEPROP 1 LAST $LOCATION C316
J 2
(-9450 4400);
DISPLAY 1.212766 (-9450 4400);
PAINT GREEN (-9450 4400);
FORCEPROP 0 LAST CDS_LOCATION C316
J 0
(-9600 4700);
DISPLAY 1.021277 (-9600 4700);
DISPLAY INVISIBLE (-9600 4700);
FORCEPROP 0 LAST $SEC 1
J 0
(-9600 4700);
DISPLAY 0.680851 (-9600 4700);
PAINT MONO (-9600 4700);
DISPLAY INVISIBLE (-9600 4700);
FORCEPROP 0 LAST CDS_SEC 1
J 0
(-9600 4700);
DISPLAY 1.021277 (-9600 4700);
DISPLAY INVISIBLE (-9600 4700);
FORCEPROP 0 LASTPIN (-9750 4700) $PN 1
R 1
J 0
(-9760 4710);
DISPLAY 0.680851 (-9760 4710);
PAINT MONO (-9760 4710);
FORCEPROP 0 LASTPIN (-9750 4450) $PN 2
R 1
J 2
(-9760 4440);
DISPLAY 0.680851 (-9760 4440);
PAINT MONO (-9760 4440);
FORCEPROP 1 LAST VALUE 0.1UF
J 2
(-9350 4500);
DISPLAY 1.212766 (-9350 4500);
PAINT GREEN (-9350 4500);
FORCEPROP 0 LAST PACKAGE 0402
J 0
(-9650 4600);
DISPLAY 1.021277 (-9650 4600);
FORCEPROP 0 LAST VOLTAGE 25V
J 0
(-9650 4700);
DISPLAY 1.021277 (-9650 4700);
FORCEPROP 1 LAST PATH I250
J 2
(-9650 4650);
DISPLAY 1.212766 (-9650 4650);
PAINT GREEN (-9650 4650);
DISPLAY INVISIBLE (-9650 4650);
FORCEPROP 1 LAST TOLERANCE 10%
J 2
(-9600 4700);
DISPLAY 1.212766 (-9600 4700);
PAINT GREEN (-9600 4700);
DISPLAY INVISIBLE (-9600 4700);
FORCEPROP 1 LAST CLS_PN G105-0B104-EK
J 2
(-9650 4650);
DISPLAY 1.212766 (-9650 4650);
PAINT GREEN (-9650 4650);
DISPLAY INVISIBLE (-9650 4650);
FORCEPROP 1 LAST CDS_LMAN_SYM_OUTLINE -50,0,50,-50
J 2
(-9750 4600);
DISPLAY 0.468085 (-9750 4600);
PAINT GREEN (-9750 4600);
DISPLAY INVISIBLE (-9750 4600);
FORCEPROP 2 LAST CDS_LIB passive
J 0
(-9750 4600);
DISPLAY INVISIBLE (-9750 4600);
FORCEADD GND_SG..1
(-9800 4350);
FORCEPROP 3 LASTPIN (-9750 4400) SIG_NAME SG\g
J 0
(-9740 4410);
DISPLAY 0.659574 (-9740 4410);
PAINT MONO (-9740 4410);
DISPLAY INVISIBLE (-9740 4410);
FORCEPROP 1 LAST HDL_POWER SG
J 1
(-9745 4255);
DISPLAY 0.808511 (-9745 4255);
PAINT GREEN (-9745 4255);
FORCEPROP 1 LAST PATH I252
J 0
(-9765 4350);
DISPLAY 0.808511 (-9765 4350);
PAINT GREEN (-9765 4350);
DISPLAY INVISIBLE (-9765 4350);
FORCEPROP 1 LAST BODY_TYPE PLUMBING
J 0
(-9785 4335);
DISPLAY 0.808511 (-9785 4335);
PAINT GREEN (-9785 4335);
DISPLAY INVISIBLE (-9785 4335);
FORCEPROP 1 LAST CDS_LMAN_SYM_OUTLINE 0,0,100,-50
J 0
(-9800 4350);
DISPLAY 0.468085 (-9800 4350);
PAINT GREEN (-9800 4350);
DISPLAY INVISIBLE (-9800 4350);
FORCEPROP 2 LAST CDS_LIB cls
J 0
(-9800 4350);
DISPLAY INVISIBLE (-9800 4350);
FORCEADD OFFPAGE_IN..2
R 2
(-13800 4800);
FORCEPROP 2 LAST $XR0 11F12> 
J 0
(-14014 4800);
DISPLAY 0.638298 (-14014 4800);
PAINT MONO (-14014 4800);
FORCEPROP 1 LAST BODY_TYPE COMMENT
J 2
(-13810 4935);
DISPLAY 0.808511 (-13810 4935);
PAINT GREEN (-13810 4935);
DISPLAY INVISIBLE (-13810 4935);
FORCEPROP 1 LAST CDS_LMAN_SYM_OUTLINE -50,50,50,-50
J 2
(-13800 4800);
DISPLAY 0.468085 (-13800 4800);
PAINT GREEN (-13800 4800);
DISPLAY INVISIBLE (-13800 4800);
FORCEPROP 2 LAST CDS_LIB cls
J 0
(-13800 4800);
DISPLAY INVISIBLE (-13800 4800);
FORCEPROP 1 LAST OFFPAGE TRUE
J 2
(-13810 4855);
DISPLAY 0.808511 (-13810 4855);
PAINT GREEN (-13810 4855);
DISPLAY INVISIBLE (-13810 4855);
FORCEPROP 2 LAST PATH I254
J 0
(-13750 4900);
DISPLAY 1.021277 (-13750 4900);
DISPLAY INVISIBLE (-13750 4900);
FORCEADD RESISTOR..1
(-11900 5200);
FORCEPROP 1 LAST $LOCATION R322
J 2
(-12100 5200);
DISPLAY 1.234043 (-12100 5200);
PAINT GREEN (-12100 5200);
FORCEPROP 0 LAST CDS_LOCATION R322
J 0
(-11700 5300);
DISPLAY 1.021277 (-11700 5300);
DISPLAY INVISIBLE (-11700 5300);
FORCEPROP 0 LAST $SEC 1
J 0
(-11700 5300);
DISPLAY 0.680851 (-11700 5300);
PAINT MONO (-11700 5300);
DISPLAY INVISIBLE (-11700 5300);
FORCEPROP 0 LAST CDS_SEC 1
J 0
(-11700 5300);
DISPLAY 1.021277 (-11700 5300);
DISPLAY INVISIBLE (-11700 5300);
FORCEPROP 0 LASTPIN (-12000 5200) $PN 1
J 2
(-12010 5210);
DISPLAY 0.680851 (-12010 5210);
PAINT MONO (-12010 5210);
FORCEPROP 0 LASTPIN (-11750 5200) $PN 2
J 0
(-11740 5210);
DISPLAY 0.680851 (-11740 5210);
PAINT MONO (-11740 5210);
FORCEPROP 0 LAST NO_ASSY TRUE
J 0
(-11950 5250);
DISPLAY 0.638298 (-11950 5250);
DISPLAY BOTH (-11950 5250);
FORCEPROP 0 LAST PACKAGE 0402
J 0
(-11950 5150);
DISPLAY 0.638298 (-11950 5150);
FORCEPROP 1 LAST VALUE 33OHM
J 0
(-11700 5200);
DISPLAY 0.978723 (-11700 5200);
PAINT GREEN (-11700 5200);
FORCEPROP 1 LAST PATH I257
J 0
(-12097 5305);
DISPLAY 1.212766 (-12097 5305);
PAINT GREEN (-12097 5305);
DISPLAY INVISIBLE (-12097 5305);
FORCEPROP 1 LAST TOLERANCE 1%
J 0
(-12097 5455);
DISPLAY 1.212766 (-12097 5455);
PAINT GREEN (-12097 5455);
DISPLAY INVISIBLE (-12097 5455);
FORCEPROP 1 LAST CLS_PN G155-133R0-01
J 0
(-12036 5400);
DISPLAY 1.212766 (-12036 5400);
PAINT GREEN (-12036 5400);
DISPLAY INVISIBLE (-12036 5400);
FORCEPROP 2 LAST CDS_LIB passive
J 0
(-11900 5200);
DISPLAY INVISIBLE (-11900 5200);
FORCEPROP 1 LAST CDS_LMAN_SYM_OUTLINE -50,50,100,-50
J 0
(-11900 5200);
DISPLAY 0.468085 (-11900 5200);
PAINT GREEN (-11900 5200);
DISPLAY INVISIBLE (-11900 5200);
FORCEPROP 2 LAST SIGNAL_MODEL DEFAULT_RESISTOR_33OHM_2_1
J 0
(-12050 5400);
DISPLAY 1.021277 (-12050 5400);
DISPLAY INVISIBLE (-12050 5400);
FORCEADD RESISTOR..1
(-11900 5300);
FORCEPROP 1 LAST $LOCATION R321
J 2
(-12100 5300);
DISPLAY 1.234043 (-12100 5300);
PAINT GREEN (-12100 5300);
FORCEPROP 0 LAST CDS_LOCATION R321
J 0
(-11700 5400);
DISPLAY 1.021277 (-11700 5400);
DISPLAY INVISIBLE (-11700 5400);
FORCEPROP 0 LAST $SEC 1
J 0
(-11700 5400);
DISPLAY 0.680851 (-11700 5400);
PAINT MONO (-11700 5400);
DISPLAY INVISIBLE (-11700 5400);
FORCEPROP 0 LAST CDS_SEC 1
J 0
(-11700 5400);
DISPLAY 1.021277 (-11700 5400);
DISPLAY INVISIBLE (-11700 5400);
FORCEPROP 0 LASTPIN (-12000 5300) $PN 1
J 2
(-12010 5310);
DISPLAY 0.680851 (-12010 5310);
PAINT MONO (-12010 5310);
FORCEPROP 0 LASTPIN (-11750 5300) $PN 2
J 0
(-11740 5310);
DISPLAY 0.680851 (-11740 5310);
PAINT MONO (-11740 5310);
FORCEPROP 1 LAST VALUE 33OHM
J 0
(-11700 5300);
DISPLAY 0.978723 (-11700 5300);
PAINT GREEN (-11700 5300);
FORCEPROP 0 LAST NO_ASSY TRUE
J 0
(-11950 5350);
DISPLAY 0.638298 (-11950 5350);
DISPLAY BOTH (-11950 5350);
FORCEPROP 0 LAST PACKAGE 0402
J 0
(-11950 5300);
DISPLAY 0.638298 (-11950 5300);
FORCEPROP 1 LAST PATH I258
J 0
(-12097 5405);
DISPLAY 1.212766 (-12097 5405);
PAINT GREEN (-12097 5405);
DISPLAY INVISIBLE (-12097 5405);
FORCEPROP 1 LAST TOLERANCE 1%
J 0
(-12097 5555);
DISPLAY 1.212766 (-12097 5555);
PAINT GREEN (-12097 5555);
DISPLAY INVISIBLE (-12097 5555);
FORCEPROP 1 LAST CLS_PN G155-133R0-01
J 0
(-12036 5500);
DISPLAY 1.212766 (-12036 5500);
PAINT GREEN (-12036 5500);
DISPLAY INVISIBLE (-12036 5500);
FORCEPROP 2 LAST SIGNAL_MODEL DEFAULT_RESISTOR_33OHM_2_1
J 0
(-12050 5500);
DISPLAY 1.021277 (-12050 5500);
DISPLAY INVISIBLE (-12050 5500);
FORCEPROP 1 LAST CDS_LMAN_SYM_OUTLINE -50,50,100,-50
J 0
(-11900 5300);
DISPLAY 0.468085 (-11900 5300);
PAINT GREEN (-11900 5300);
DISPLAY INVISIBLE (-11900 5300);
FORCEPROP 2 LAST CDS_LIB passive
J 0
(-11900 5300);
DISPLAY INVISIBLE (-11900 5300);
FORCEADD RESISTOR..2
(-11400 5850);
FORCEPROP 1 LAST $LOCATION R317
J 0
(-11350 5700);
DISPLAY 1.212766 (-11350 5700);
PAINT GREEN (-11350 5700);
FORCEPROP 0 LAST CDS_LOCATION R317
J 0
(-11350 6050);
DISPLAY 1.021277 (-11350 6050);
DISPLAY INVISIBLE (-11350 6050);
FORCEPROP 0 LAST $SEC 1
J 0
(-11350 6050);
DISPLAY 0.680851 (-11350 6050);
PAINT MONO (-11350 6050);
DISPLAY INVISIBLE (-11350 6050);
FORCEPROP 0 LAST CDS_SEC 1
J 0
(-11350 6050);
DISPLAY 1.021277 (-11350 6050);
DISPLAY INVISIBLE (-11350 6050);
FORCEPROP 0 LASTPIN (-11400 5950) $PN 1
R 1
J 0
(-11410 5960);
DISPLAY 0.680851 (-11410 5960);
PAINT MONO (-11410 5960);
FORCEPROP 0 LASTPIN (-11400 5700) $PN 2
R 1
J 2
(-11410 5690);
DISPLAY 0.680851 (-11410 5690);
PAINT MONO (-11410 5690);
FORCEPROP 0 LAST PACKAGE 0402
J 0
(-11350 6000);
DISPLAY 1.021277 (-11350 6000);
FORCEPROP 1 LAST VALUE 10KOHM
J 0
(-11350 5900);
DISPLAY 0.978723 (-11350 5900);
PAINT GREEN (-11350 5900);
FORCEPROP 1 LAST PATH I259
J 0
(-11597 5955);
DISPLAY 1.212766 (-11597 5955);
PAINT GREEN (-11597 5955);
DISPLAY INVISIBLE (-11597 5955);
FORCEPROP 1 LAST TOLERANCE 1%
J 0
(-11597 6105);
DISPLAY 1.212766 (-11597 6105);
PAINT GREEN (-11597 6105);
DISPLAY INVISIBLE (-11597 6105);
FORCEPROP 2 LAST CDS_LIB passive
J 0
(-11400 5850);
DISPLAY INVISIBLE (-11400 5850);
FORCEPROP 1 LAST CDS_LMAN_SYM_OUTLINE -50,50,50,-100
J 0
(-11400 5850);
DISPLAY 0.468085 (-11400 5850);
PAINT GREEN (-11400 5850);
DISPLAY INVISIBLE (-11400 5850);
FORCEPROP 1 LAST CLS_PN G155-11002-01
J 0
(-11536 6050);
DISPLAY 1.212766 (-11536 6050);
PAINT GREEN (-11536 6050);
DISPLAY INVISIBLE (-11536 6050);
FORCEADD RESISTOR..2
(-11000 5850);
FORCEPROP 1 LAST $LOCATION R318
J 0
(-10950 5700);
DISPLAY 1.212766 (-10950 5700);
PAINT GREEN (-10950 5700);
FORCEPROP 0 LAST CDS_LOCATION R318
J 0
(-10950 6050);
DISPLAY 1.021277 (-10950 6050);
DISPLAY INVISIBLE (-10950 6050);
FORCEPROP 0 LAST $SEC 1
J 0
(-10950 6050);
DISPLAY 0.680851 (-10950 6050);
PAINT MONO (-10950 6050);
DISPLAY INVISIBLE (-10950 6050);
FORCEPROP 0 LAST CDS_SEC 1
J 0
(-10950 6050);
DISPLAY 1.021277 (-10950 6050);
DISPLAY INVISIBLE (-10950 6050);
FORCEPROP 0 LASTPIN (-11000 5950) $PN 1
R 1
J 0
(-11010 5960);
DISPLAY 0.680851 (-11010 5960);
PAINT MONO (-11010 5960);
FORCEPROP 0 LASTPIN (-11000 5700) $PN 2
R 1
J 2
(-11010 5690);
DISPLAY 0.680851 (-11010 5690);
PAINT MONO (-11010 5690);
FORCEPROP 0 LAST PACKAGE 0402
J 0
(-10950 6000);
DISPLAY 1.021277 (-10950 6000);
FORCEPROP 1 LAST VALUE 10KOHM
J 0
(-10950 5900);
DISPLAY 0.978723 (-10950 5900);
PAINT GREEN (-10950 5900);
FORCEPROP 1 LAST PATH I261
J 0
(-11197 5955);
DISPLAY 1.212766 (-11197 5955);
PAINT GREEN (-11197 5955);
DISPLAY INVISIBLE (-11197 5955);
FORCEPROP 1 LAST TOLERANCE 1%
J 0
(-11197 6105);
DISPLAY 1.212766 (-11197 6105);
PAINT GREEN (-11197 6105);
DISPLAY INVISIBLE (-11197 6105);
FORCEPROP 2 LAST CDS_LIB passive
J 0
(-11000 5850);
DISPLAY INVISIBLE (-11000 5850);
FORCEPROP 1 LAST CDS_LMAN_SYM_OUTLINE -50,50,50,-100
J 0
(-11000 5850);
DISPLAY 0.468085 (-11000 5850);
PAINT GREEN (-11000 5850);
DISPLAY INVISIBLE (-11000 5850);
FORCEPROP 1 LAST CLS_PN G155-11002-01
J 0
(-11136 6050);
DISPLAY 1.212766 (-11136 6050);
PAINT GREEN (-11136 6050);
DISPLAY INVISIBLE (-11136 6050);
FORCEADD OFFPAGE_IN..2
R 2
(-13800 5200);
FORCEPROP 2 LAST $XR0 11F12> 
J 0
(-14014 5200);
DISPLAY 0.638298 (-14014 5200);
PAINT MONO (-14014 5200);
FORCEPROP 2 LAST PATH I262
J 0
(-13950 5250);
DISPLAY 1.021277 (-13950 5250);
DISPLAY INVISIBLE (-13950 5250);
FORCEPROP 1 LAST OFFPAGE TRUE
J 2
(-13810 5255);
DISPLAY 0.808511 (-13810 5255);
PAINT GREEN (-13810 5255);
DISPLAY INVISIBLE (-13810 5255);
FORCEPROP 2 LAST CDS_LIB cls
J 0
(-13800 5200);
DISPLAY INVISIBLE (-13800 5200);
FORCEPROP 1 LAST CDS_LMAN_SYM_OUTLINE -50,50,50,-50
J 2
(-13800 5200);
DISPLAY 0.468085 (-13800 5200);
PAINT GREEN (-13800 5200);
DISPLAY INVISIBLE (-13800 5200);
FORCEPROP 1 LAST BODY_TYPE COMMENT
J 2
(-13810 5335);
DISPLAY 0.808511 (-13810 5335);
PAINT GREEN (-13810 5335);
DISPLAY INVISIBLE (-13810 5335);
FORCEADD OFFPAGE_BI..1
R 2
(-13800 5300);
FORCEPROP 2 LAST $XR0 11F12<> 
J 0
(-14050 5300);
DISPLAY 0.638298 (-14050 5300);
PAINT MONO (-14050 5300);
FORCEPROP 2 LAST PATH I263
J 0
(-13950 5350);
DISPLAY 1.021277 (-13950 5350);
DISPLAY INVISIBLE (-13950 5350);
FORCEPROP 1 LAST OFFPAGE TRUE
J 2
(-13810 5355);
DISPLAY 0.808511 (-13810 5355);
PAINT GREEN (-13810 5355);
DISPLAY INVISIBLE (-13810 5355);
FORCEPROP 1 LAST BODY_TYPE COMMENT
J 2
(-13810 5435);
DISPLAY 0.808511 (-13810 5435);
PAINT GREEN (-13810 5435);
DISPLAY INVISIBLE (-13810 5435);
FORCEPROP 1 LAST CDS_LMAN_SYM_OUTLINE -50,50,50,-50
J 2
(-13800 5300);
DISPLAY 0.468085 (-13800 5300);
PAINT GREEN (-13800 5300);
DISPLAY INVISIBLE (-13800 5300);
FORCEPROP 2 LAST CDS_LIB cls
J 0
(-13800 5300);
PAINT MONO (-13800 5300);
DISPLAY INVISIBLE (-13800 5300);
FORCEADD RESISTOR..2
(-9700 5500);
FORCEPROP 1 LAST LOCATION R320
J 0
(-9650 5300);
DISPLAY 1.212766 (-9650 5300);
PAINT GREEN (-9650 5300);
FORCEPROP 0 LAST $SEC 1
J 0
(-9650 5700);
DISPLAY 0.680851 (-9650 5700);
PAINT MONO (-9650 5700);
DISPLAY INVISIBLE (-9650 5700);
FORCEPROP 0 LAST CDS_SEC 1
J 0
(-9650 5700);
DISPLAY 1.021277 (-9650 5700);
DISPLAY INVISIBLE (-9650 5700);
FORCEPROP 0 LASTPIN (-9700 5600) $PN 1
R 1
J 0
(-9710 5610);
DISPLAY 0.680851 (-9710 5610);
PAINT MONO (-9710 5610);
FORCEPROP 0 LASTPIN (-9700 5350) $PN 2
R 1
J 2
(-9710 5340);
DISPLAY 0.680851 (-9710 5340);
PAINT MONO (-9710 5340);
FORCEPROP 0 LAST PACKAGE 0402
J 0
(-9650 5500);
DISPLAY 1.021277 (-9650 5500);
FORCEPROP 1 LAST VALUE 4.7KOHM
J 0
(-9650 5400);
DISPLAY 0.978723 (-9650 5400);
PAINT GREEN (-9650 5400);
FORCEPROP 1 LAST PATH I264
J 0
(-9897 5605);
DISPLAY 1.212766 (-9897 5605);
PAINT GREEN (-9897 5605);
DISPLAY INVISIBLE (-9897 5605);
FORCEPROP 1 LAST TOLERANCE 1%
J 0
(-9897 5755);
DISPLAY 1.212766 (-9897 5755);
PAINT GREEN (-9897 5755);
DISPLAY INVISIBLE (-9897 5755);
FORCEPROP 2 LAST CDS_LIB passive
J 0
(-9700 5500);
DISPLAY INVISIBLE (-9700 5500);
FORCEPROP 1 LAST CDS_LMAN_SYM_OUTLINE -50,50,50,-100
J 0
(-9700 5500);
DISPLAY 0.468085 (-9700 5500);
PAINT GREEN (-9700 5500);
DISPLAY INVISIBLE (-9700 5500);
FORCEPROP 1 LAST CLS_PN G155-14701-01
J 0
(-9836 5700);
DISPLAY 1.212766 (-9836 5700);
PAINT GREEN (-9836 5700);
DISPLAY INVISIBLE (-9836 5700);
FORCEADD LED_4P_V14..1
R 2
(-1200 11650);
FORCEPROP 1 LAST LOCATION DS14
J 2
(-1200 11700);
DISPLAY 1.212766 (-1200 11700);
PAINT GREEN (-1200 11700);
FORCEPROP 0 LAST $SEC 1
J 0
(-1250 11950);
DISPLAY 0.680851 (-1250 11950);
PAINT MONO (-1250 11950);
DISPLAY INVISIBLE (-1250 11950);
FORCEPROP 0 LAST CDS_SEC 1
J 0
(-1250 11950);
DISPLAY 1.021277 (-1250 11950);
DISPLAY INVISIBLE (-1250 11950);
FORCEPROP 0 LASTPIN (-2000 10750) $PN 1
J 2
(-2010 10760);
DISPLAY 0.680851 (-2010 10760);
PAINT MONO (-2010 10760);
FORCEPROP 0 LASTPIN (-1100 11050) $PN 2
J 0
(-1090 11060);
DISPLAY 0.680851 (-1090 11060);
PAINT MONO (-1090 11060);
FORCEPROP 0 LASTPIN (-2000 11050) $PN 3
J 2
(-2010 11060);
DISPLAY 0.680851 (-2010 11060);
PAINT MONO (-2010 11060);
FORCEPROP 0 LASTPIN (-2000 11350) $PN 4
J 2
(-2010 11360);
DISPLAY 0.680851 (-2010 11360);
PAINT MONO (-2010 11360);
FORCEPROP 0 LAST PART_NUMBER APFA2507QBDSEEZGKC
J 0
(-1950 11900);
DISPLAY 1.021277 (-1950 11900);
FORCEPROP 1 LAST CLS_PN G170-10189-01
J 2
(-1200 11800);
DISPLAY 1.212766 (-1200 11800);
PAINT GREEN (-1200 11800);
FORCEPROP 2 LASTPIN (-2000 11350) SIG_NAME UN$14$LED4PV14$I265$4
J 0
(-1990 11360);
DISPLAY 0.659574 (-1990 11360);
PAINT MONO (-1990 11360);
DISPLAY INVISIBLE (-1990 11360);
FORCEPROP 2 LASTPIN (-2000 11050) SIG_NAME UN$14$LED4PV14$I265$3
J 0
(-1990 11060);
DISPLAY 0.659574 (-1990 11060);
PAINT MONO (-1990 11060);
DISPLAY INVISIBLE (-1990 11060);
FORCEPROP 2 LASTPIN (-2000 10750) SIG_NAME UN$14$LED4PV14$I265$1
J 0
(-1990 10760);
DISPLAY 0.659574 (-1990 10760);
PAINT MONO (-1990 10760);
DISPLAY INVISIBLE (-1990 10760);
FORCEPROP 1 LAST CDS_LMAN_SYM_OUTLINE 0,0,700,-1150
J 2
(-1200 11650);
DISPLAY 0.468085 (-1200 11650);
PAINT GREEN (-1200 11650);
DISPLAY INVISIBLE (-1200 11650);
FORCEPROP 2 LAST CDS_LIB discrete
J 2
(-1200 11650);
DISPLAY INVISIBLE (-1200 11650);
FORCEPROP 1 LAST PATH I265
J 2
(-1250 11700);
DISPLAY 1.212766 (-1250 11700);
PAINT GREEN (-1250 11700);
DISPLAY INVISIBLE (-1250 11700);
FORCEADD LED_4P_V14..1
R 2
(-1200 10150);
FORCEPROP 1 LAST LOCATION DS15
J 2
(-1150 10200);
DISPLAY 1.212766 (-1150 10200);
PAINT GREEN (-1150 10200);
FORCEPROP 0 LAST $SEC 1
J 0
(-1250 10450);
DISPLAY 0.680851 (-1250 10450);
PAINT MONO (-1250 10450);
DISPLAY INVISIBLE (-1250 10450);
FORCEPROP 0 LAST CDS_SEC 1
J 0
(-1250 10450);
DISPLAY 1.021277 (-1250 10450);
DISPLAY INVISIBLE (-1250 10450);
FORCEPROP 0 LASTPIN (-2000 9250) $PN 1
J 2
(-2010 9260);
DISPLAY 0.680851 (-2010 9260);
PAINT MONO (-2010 9260);
FORCEPROP 0 LASTPIN (-1100 9550) $PN 2
J 0
(-1090 9560);
DISPLAY 0.680851 (-1090 9560);
PAINT MONO (-1090 9560);
FORCEPROP 0 LASTPIN (-2000 9550) $PN 3
J 2
(-2010 9560);
DISPLAY 0.680851 (-2010 9560);
PAINT MONO (-2010 9560);
FORCEPROP 0 LASTPIN (-2000 9850) $PN 4
J 2
(-2010 9860);
DISPLAY 0.680851 (-2010 9860);
PAINT MONO (-2010 9860);
FORCEPROP 1 LAST CLS_PN G170-10189-01
J 2
(-1150 10300);
DISPLAY 1.212766 (-1150 10300);
PAINT GREEN (-1150 10300);
FORCEPROP 0 LAST PART_NUMBER APFA2507QBDSEEZGKC
J 0
(-1900 10400);
DISPLAY 1.021277 (-1900 10400);
FORCEPROP 2 LASTPIN (-2000 9850) SIG_NAME UN$14$LED4PV14$I266$4
J 0
(-1990 9860);
DISPLAY 0.659574 (-1990 9860);
PAINT MONO (-1990 9860);
DISPLAY INVISIBLE (-1990 9860);
FORCEPROP 2 LASTPIN (-2000 9550) SIG_NAME UN$14$LED4PV14$I266$3
J 0
(-1990 9560);
DISPLAY 0.659574 (-1990 9560);
PAINT MONO (-1990 9560);
DISPLAY INVISIBLE (-1990 9560);
FORCEPROP 2 LASTPIN (-2000 9250) SIG_NAME UN$14$LED4PV14$I266$1
J 0
(-1990 9260);
DISPLAY 0.659574 (-1990 9260);
PAINT MONO (-1990 9260);
DISPLAY INVISIBLE (-1990 9260);
FORCEPROP 2 LAST CDS_LIB discrete
J 0
(-1200 10150);
DISPLAY INVISIBLE (-1200 10150);
FORCEPROP 1 LAST CDS_LMAN_SYM_OUTLINE 0,0,700,-1150
J 2
(-1200 10150);
DISPLAY 0.468085 (-1200 10150);
PAINT GREEN (-1200 10150);
DISPLAY INVISIBLE (-1200 10150);
FORCEPROP 1 LAST PATH I266
J 2
(-1250 10200);
DISPLAY 1.212766 (-1250 10200);
PAINT GREEN (-1250 10200);
DISPLAY INVISIBLE (-1250 10200);
FORCEADD LED_4P_V14..1
R 2
(-1200 8600);
FORCEPROP 1 LAST LOCATION DS16
J 2
(-1200 8650);
DISPLAY 1.212766 (-1200 8650);
PAINT GREEN (-1200 8650);
FORCEPROP 0 LAST $SEC 1
J 0
(-1250 8900);
DISPLAY 0.680851 (-1250 8900);
PAINT MONO (-1250 8900);
DISPLAY INVISIBLE (-1250 8900);
FORCEPROP 0 LAST CDS_SEC 1
J 0
(-1250 8900);
DISPLAY 1.021277 (-1250 8900);
DISPLAY INVISIBLE (-1250 8900);
FORCEPROP 0 LASTPIN (-2000 7700) $PN 1
J 2
(-2010 7710);
DISPLAY 0.680851 (-2010 7710);
PAINT MONO (-2010 7710);
FORCEPROP 0 LASTPIN (-1100 8000) $PN 2
J 0
(-1090 8010);
DISPLAY 0.680851 (-1090 8010);
PAINT MONO (-1090 8010);
FORCEPROP 0 LASTPIN (-2000 8000) $PN 3
J 2
(-2010 8010);
DISPLAY 0.680851 (-2010 8010);
PAINT MONO (-2010 8010);
FORCEPROP 0 LASTPIN (-2000 8300) $PN 4
J 2
(-2010 8310);
DISPLAY 0.680851 (-2010 8310);
PAINT MONO (-2010 8310);
FORCEPROP 1 LAST CLS_PN G170-10189-01
J 2
(-1200 8750);
DISPLAY 1.212766 (-1200 8750);
PAINT GREEN (-1200 8750);
FORCEPROP 0 LAST PART_NUMBER APFA2507QBDSEEZGKC
J 0
(-1950 8850);
DISPLAY 1.021277 (-1950 8850);
FORCEPROP 2 LASTPIN (-2000 8300) SIG_NAME UN$14$LED4PV14$I267$4
J 0
(-1990 8310);
DISPLAY 0.659574 (-1990 8310);
PAINT MONO (-1990 8310);
DISPLAY INVISIBLE (-1990 8310);
FORCEPROP 2 LASTPIN (-2000 8000) SIG_NAME UN$14$LED4PV14$I267$3
J 0
(-1990 8010);
DISPLAY 0.659574 (-1990 8010);
PAINT MONO (-1990 8010);
DISPLAY INVISIBLE (-1990 8010);
FORCEPROP 2 LASTPIN (-2000 7700) SIG_NAME UN$14$LED4PV14$I267$1
J 0
(-1990 7710);
DISPLAY 0.659574 (-1990 7710);
PAINT MONO (-1990 7710);
DISPLAY INVISIBLE (-1990 7710);
FORCEPROP 2 LAST CDS_LIB discrete
J 0
(-1200 8600);
DISPLAY INVISIBLE (-1200 8600);
FORCEPROP 1 LAST CDS_LMAN_SYM_OUTLINE 0,0,700,-1150
J 2
(-1200 8600);
DISPLAY 0.468085 (-1200 8600);
PAINT GREEN (-1200 8600);
DISPLAY INVISIBLE (-1200 8600);
FORCEPROP 1 LAST PATH I267
J 2
(-1250 8650);
DISPLAY 1.212766 (-1250 8650);
PAINT GREEN (-1250 8650);
DISPLAY INVISIBLE (-1250 8650);
FORCEADD LED_4P_V14..1
R 2
(-1200 7050);
FORCEPROP 1 LAST LOCATION DS17
J 2
(-1150 7100);
DISPLAY 1.212766 (-1150 7100);
PAINT GREEN (-1150 7100);
FORCEPROP 0 LAST $SEC 1
J 0
(-1250 7350);
DISPLAY 0.680851 (-1250 7350);
PAINT MONO (-1250 7350);
DISPLAY INVISIBLE (-1250 7350);
FORCEPROP 0 LAST CDS_SEC 1
J 0
(-1250 7350);
DISPLAY 1.021277 (-1250 7350);
DISPLAY INVISIBLE (-1250 7350);
FORCEPROP 0 LASTPIN (-2000 6150) $PN 1
J 2
(-2010 6160);
DISPLAY 0.680851 (-2010 6160);
PAINT MONO (-2010 6160);
FORCEPROP 0 LASTPIN (-1100 6450) $PN 2
J 0
(-1090 6460);
DISPLAY 0.680851 (-1090 6460);
PAINT MONO (-1090 6460);
FORCEPROP 0 LASTPIN (-2000 6450) $PN 3
J 2
(-2010 6460);
DISPLAY 0.680851 (-2010 6460);
PAINT MONO (-2010 6460);
FORCEPROP 0 LASTPIN (-2000 6750) $PN 4
J 2
(-2010 6760);
DISPLAY 0.680851 (-2010 6760);
PAINT MONO (-2010 6760);
FORCEPROP 1 LAST CLS_PN G170-10189-01
J 2
(-1150 7200);
DISPLAY 1.212766 (-1150 7200);
PAINT GREEN (-1150 7200);
FORCEPROP 0 LAST PART_NUMBER APFA2507QBDSEEZGKC
J 0
(-1900 7300);
DISPLAY 1.021277 (-1900 7300);
FORCEPROP 2 LASTPIN (-2000 6750) SIG_NAME UN$14$LED4PV14$I268$4
J 0
(-1990 6760);
DISPLAY 0.659574 (-1990 6760);
PAINT MONO (-1990 6760);
DISPLAY INVISIBLE (-1990 6760);
FORCEPROP 2 LASTPIN (-2000 6450) SIG_NAME UN$14$LED4PV14$I268$3
J 0
(-1990 6460);
DISPLAY 0.659574 (-1990 6460);
PAINT MONO (-1990 6460);
DISPLAY INVISIBLE (-1990 6460);
FORCEPROP 2 LASTPIN (-2000 6150) SIG_NAME UN$14$LED4PV14$I268$1
J 0
(-1990 6160);
DISPLAY 0.659574 (-1990 6160);
PAINT MONO (-1990 6160);
DISPLAY INVISIBLE (-1990 6160);
FORCEPROP 1 LAST CDS_LMAN_SYM_OUTLINE 0,0,700,-1150
J 2
(-1200 7050);
DISPLAY 0.468085 (-1200 7050);
PAINT GREEN (-1200 7050);
DISPLAY INVISIBLE (-1200 7050);
FORCEPROP 2 LAST CDS_LIB discrete
J 0
(-1200 7050);
DISPLAY INVISIBLE (-1200 7050);
FORCEPROP 1 LAST PATH I268
J 2
(-1250 7100);
DISPLAY 1.212766 (-1250 7100);
PAINT GREEN (-1250 7100);
DISPLAY INVISIBLE (-1250 7100);
FORCEADD LED_4P_V14..1
R 2
(-1200 5500);
FORCEPROP 1 LAST LOCATION DS18
J 2
(-1200 5550);
DISPLAY 1.212766 (-1200 5550);
PAINT GREEN (-1200 5550);
FORCEPROP 0 LAST $SEC 1
J 0
(-1250 5800);
DISPLAY 0.680851 (-1250 5800);
PAINT MONO (-1250 5800);
DISPLAY INVISIBLE (-1250 5800);
FORCEPROP 0 LAST CDS_SEC 1
J 0
(-1250 5800);
DISPLAY 1.021277 (-1250 5800);
DISPLAY INVISIBLE (-1250 5800);
FORCEPROP 0 LASTPIN (-2000 4600) $PN 1
J 2
(-2010 4610);
DISPLAY 0.680851 (-2010 4610);
PAINT MONO (-2010 4610);
FORCEPROP 0 LASTPIN (-1100 4900) $PN 2
J 0
(-1090 4910);
DISPLAY 0.680851 (-1090 4910);
PAINT MONO (-1090 4910);
FORCEPROP 0 LASTPIN (-2000 4900) $PN 3
J 2
(-2010 4910);
DISPLAY 0.680851 (-2010 4910);
PAINT MONO (-2010 4910);
FORCEPROP 0 LASTPIN (-2000 5200) $PN 4
J 2
(-2010 5210);
DISPLAY 0.680851 (-2010 5210);
PAINT MONO (-2010 5210);
FORCEPROP 1 LAST CLS_PN G170-10189-01
J 2
(-1200 5650);
DISPLAY 1.212766 (-1200 5650);
PAINT GREEN (-1200 5650);
FORCEPROP 0 LAST PART_NUMBER APFA2507QBDSEEZGKC
J 0
(-1950 5750);
DISPLAY 1.021277 (-1950 5750);
FORCEPROP 2 LAST CDS_LIB discrete
J 0
(-1200 5500);
DISPLAY INVISIBLE (-1200 5500);
FORCEPROP 1 LAST CDS_LMAN_SYM_OUTLINE 0,0,700,-1150
J 2
(-1200 5500);
DISPLAY 0.468085 (-1200 5500);
PAINT GREEN (-1200 5500);
DISPLAY INVISIBLE (-1200 5500);
FORCEPROP 2 LASTPIN (-2000 4600) SIG_NAME UN$14$LED4PV14$I269$1
J 0
(-1990 4610);
DISPLAY 0.659574 (-1990 4610);
PAINT MONO (-1990 4610);
DISPLAY INVISIBLE (-1990 4610);
FORCEPROP 2 LASTPIN (-2000 4900) SIG_NAME UN$14$LED4PV14$I269$3
J 0
(-1990 4910);
DISPLAY 0.659574 (-1990 4910);
PAINT MONO (-1990 4910);
DISPLAY INVISIBLE (-1990 4910);
FORCEPROP 2 LASTPIN (-2000 5200) SIG_NAME UN$14$LED4PV14$I269$4
J 0
(-1990 5210);
DISPLAY 0.659574 (-1990 5210);
PAINT MONO (-1990 5210);
DISPLAY INVISIBLE (-1990 5210);
FORCEPROP 1 LAST PATH I269
J 2
(-1250 5550);
DISPLAY 1.212766 (-1250 5550);
PAINT GREEN (-1250 5550);
DISPLAY INVISIBLE (-1250 5550);
FORCEADD OFFPAGE_OUT..1
R 6
(-6700 5600);
FORCEPROP 2 LAST $XR0 26C12> 
J 0
(-6645 5600);
DISPLAY 0.638298 (-6645 5600);
PAINT MONO (-6645 5600);
FORCEPROP 1 LAST BODY_TYPE COMMENT
J 0
(-6690 5427);
DISPLAY 0.808511 (-6690 5427);
PAINT GREEN (-6690 5427);
DISPLAY INVISIBLE (-6690 5427);
FORCEPROP 2 LAST CDS_LIB cls
J 0
(-6700 5600);
DISPLAY INVISIBLE (-6700 5600);
FORCEPROP 1 LAST CDS_LMAN_SYM_OUTLINE -50,50,50,-50
J 0
(-6700 5600);
DISPLAY 0.468085 (-6700 5600);
PAINT GREEN (-6700 5600);
DISPLAY INVISIBLE (-6700 5600);
FORCEPROP 1 LAST OFFPAGE TRUE
J 0
(-6690 5507);
DISPLAY 0.808511 (-6690 5507);
PAINT GREEN (-6690 5507);
DISPLAY INVISIBLE (-6690 5507);
FORCEPROP 2 LAST PATH I270
J 0
(-6600 5650);
DISPLAY 1.021277 (-6600 5650);
DISPLAY INVISIBLE (-6600 5650);
FORCEADD OFFPAGE_OUT..1
R 6
(-6700 5500);
FORCEPROP 2 LAST $XR0 26D12> 
J 0
(-6645 5500);
DISPLAY 0.638298 (-6645 5500);
PAINT MONO (-6645 5500);
FORCEPROP 1 LAST BODY_TYPE COMMENT
J 0
(-6690 5327);
DISPLAY 0.808511 (-6690 5327);
PAINT GREEN (-6690 5327);
DISPLAY INVISIBLE (-6690 5327);
FORCEPROP 2 LAST CDS_LIB cls
J 0
(-6700 5500);
DISPLAY INVISIBLE (-6700 5500);
FORCEPROP 1 LAST CDS_LMAN_SYM_OUTLINE -50,50,50,-50
J 0
(-6700 5500);
DISPLAY 0.468085 (-6700 5500);
PAINT GREEN (-6700 5500);
DISPLAY INVISIBLE (-6700 5500);
FORCEPROP 1 LAST OFFPAGE TRUE
J 0
(-6690 5407);
DISPLAY 0.808511 (-6690 5407);
PAINT GREEN (-6690 5407);
DISPLAY INVISIBLE (-6690 5407);
FORCEPROP 2 LAST PATH I277
J 0
(-6600 5550);
DISPLAY 1.021277 (-6600 5550);
DISPLAY INVISIBLE (-6600 5550);
FORCEADD OFFPAGE_OUT..1
R 6
(-6700 5400);
FORCEPROP 2 LAST $XR0 26D12> 
J 0
(-6645 5400);
DISPLAY 0.638298 (-6645 5400);
PAINT MONO (-6645 5400);
FORCEPROP 1 LAST BODY_TYPE COMMENT
J 0
(-6690 5227);
DISPLAY 0.808511 (-6690 5227);
PAINT GREEN (-6690 5227);
DISPLAY INVISIBLE (-6690 5227);
FORCEPROP 2 LAST CDS_LIB cls
J 0
(-6700 5400);
DISPLAY INVISIBLE (-6700 5400);
FORCEPROP 1 LAST CDS_LMAN_SYM_OUTLINE -50,50,50,-50
J 0
(-6700 5400);
DISPLAY 0.468085 (-6700 5400);
PAINT GREEN (-6700 5400);
DISPLAY INVISIBLE (-6700 5400);
FORCEPROP 1 LAST OFFPAGE TRUE
J 0
(-6690 5307);
DISPLAY 0.808511 (-6690 5307);
PAINT GREEN (-6690 5307);
DISPLAY INVISIBLE (-6690 5307);
FORCEPROP 2 LAST PATH I278
J 0
(-6600 5450);
DISPLAY 1.021277 (-6600 5450);
DISPLAY INVISIBLE (-6600 5450);
FORCEADD OFFPAGE_OUT..1
R 6
(-6700 5100);
FORCEPROP 2 LAST $XR0 26E12> 
J 0
(-6645 5100);
DISPLAY 0.638298 (-6645 5100);
PAINT MONO (-6645 5100);
FORCEPROP 1 LAST BODY_TYPE COMMENT
J 0
(-6690 4927);
DISPLAY 0.808511 (-6690 4927);
PAINT GREEN (-6690 4927);
DISPLAY INVISIBLE (-6690 4927);
FORCEPROP 2 LAST CDS_LIB cls
J 0
(-6700 5100);
DISPLAY INVISIBLE (-6700 5100);
FORCEPROP 1 LAST CDS_LMAN_SYM_OUTLINE -50,50,50,-50
J 0
(-6700 5100);
DISPLAY 0.468085 (-6700 5100);
PAINT GREEN (-6700 5100);
DISPLAY INVISIBLE (-6700 5100);
FORCEPROP 1 LAST OFFPAGE TRUE
J 0
(-6690 5007);
DISPLAY 0.808511 (-6690 5007);
PAINT GREEN (-6690 5007);
DISPLAY INVISIBLE (-6690 5007);
FORCEPROP 2 LAST PATH I279
J 0
(-6600 5150);
DISPLAY 1.021277 (-6600 5150);
DISPLAY INVISIBLE (-6600 5150);
FORCEADD OFFPAGE_OUT..1
R 6
(-6700 5300);
FORCEPROP 2 LAST $XR0 26E12> 
J 0
(-6645 5300);
DISPLAY 0.638298 (-6645 5300);
PAINT MONO (-6645 5300);
FORCEPROP 1 LAST BODY_TYPE COMMENT
J 0
(-6690 5127);
DISPLAY 0.808511 (-6690 5127);
PAINT GREEN (-6690 5127);
DISPLAY INVISIBLE (-6690 5127);
FORCEPROP 2 LAST CDS_LIB cls
J 0
(-6700 5300);
DISPLAY INVISIBLE (-6700 5300);
FORCEPROP 1 LAST CDS_LMAN_SYM_OUTLINE -50,50,50,-50
J 0
(-6700 5300);
DISPLAY 0.468085 (-6700 5300);
PAINT GREEN (-6700 5300);
DISPLAY INVISIBLE (-6700 5300);
FORCEPROP 1 LAST OFFPAGE TRUE
J 0
(-6690 5207);
DISPLAY 0.808511 (-6690 5207);
PAINT GREEN (-6690 5207);
DISPLAY INVISIBLE (-6690 5207);
FORCEPROP 2 LAST PATH I280
J 0
(-6600 5350);
DISPLAY 1.021277 (-6600 5350);
DISPLAY INVISIBLE (-6600 5350);
FORCEADD OFFPAGE_OUT..1
R 6
(-6700 5200);
FORCEPROP 2 LAST $XR0 26E12> 
J 0
(-6645 5200);
DISPLAY 0.638298 (-6645 5200);
PAINT MONO (-6645 5200);
FORCEPROP 1 LAST BODY_TYPE COMMENT
J 0
(-6690 5027);
DISPLAY 0.808511 (-6690 5027);
PAINT GREEN (-6690 5027);
DISPLAY INVISIBLE (-6690 5027);
FORCEPROP 2 LAST CDS_LIB cls
J 0
(-6700 5200);
DISPLAY INVISIBLE (-6700 5200);
FORCEPROP 1 LAST CDS_LMAN_SYM_OUTLINE -50,50,50,-50
J 0
(-6700 5200);
DISPLAY 0.468085 (-6700 5200);
PAINT GREEN (-6700 5200);
DISPLAY INVISIBLE (-6700 5200);
FORCEPROP 1 LAST OFFPAGE TRUE
J 0
(-6690 5107);
DISPLAY 0.808511 (-6690 5107);
PAINT GREEN (-6690 5107);
DISPLAY INVISIBLE (-6690 5107);
FORCEPROP 2 LAST PATH I281
J 0
(-6600 5250);
DISPLAY 1.021277 (-6600 5250);
DISPLAY INVISIBLE (-6600 5250);
FORCEADD OFFPAGE_OUT..1
R 6
(-6700 4500);
FORCEPROP 2 LAST $XR0 26J12> 
J 0
(-6645 4500);
DISPLAY 0.638298 (-6645 4500);
PAINT MONO (-6645 4500);
FORCEPROP 1 LAST CDS_LMAN_SYM_OUTLINE -50,50,50,-50
J 0
(-6700 4500);
DISPLAY 0.468085 (-6700 4500);
PAINT GREEN (-6700 4500);
DISPLAY INVISIBLE (-6700 4500);
FORCEPROP 2 LAST CDS_LIB cls
J 0
(-6700 4500);
DISPLAY INVISIBLE (-6700 4500);
FORCEPROP 1 LAST BODY_TYPE COMMENT
J 0
(-6690 4327);
DISPLAY 0.808511 (-6690 4327);
PAINT GREEN (-6690 4327);
DISPLAY INVISIBLE (-6690 4327);
FORCEPROP 1 LAST OFFPAGE TRUE
J 0
(-6690 4407);
DISPLAY 0.808511 (-6690 4407);
PAINT GREEN (-6690 4407);
DISPLAY INVISIBLE (-6690 4407);
FORCEPROP 2 LAST PATH I282
J 0
(-6600 4550);
DISPLAY 1.021277 (-6600 4550);
DISPLAY INVISIBLE (-6600 4550);
FORCEADD OFFPAGE_OUT..1
R 6
(-6700 5000);
FORCEPROP 2 LAST $XR0 26F12> 
J 0
(-6645 5000);
DISPLAY 0.638298 (-6645 5000);
PAINT MONO (-6645 5000);
FORCEPROP 1 LAST CDS_LMAN_SYM_OUTLINE -50,50,50,-50
J 0
(-6700 5000);
DISPLAY 0.468085 (-6700 5000);
PAINT GREEN (-6700 5000);
DISPLAY INVISIBLE (-6700 5000);
FORCEPROP 2 LAST CDS_LIB cls
J 0
(-6700 5000);
DISPLAY INVISIBLE (-6700 5000);
FORCEPROP 1 LAST BODY_TYPE COMMENT
J 0
(-6690 4827);
DISPLAY 0.808511 (-6690 4827);
PAINT GREEN (-6690 4827);
DISPLAY INVISIBLE (-6690 4827);
FORCEPROP 1 LAST OFFPAGE TRUE
J 0
(-6690 4907);
DISPLAY 0.808511 (-6690 4907);
PAINT GREEN (-6690 4907);
DISPLAY INVISIBLE (-6690 4907);
FORCEPROP 2 LAST PATH I283
J 0
(-6600 5050);
DISPLAY 1.021277 (-6600 5050);
DISPLAY INVISIBLE (-6600 5050);
FORCEADD OFFPAGE_OUT..1
R 6
(-6700 4800);
FORCEPROP 2 LAST $XR0 26G12> 
J 0
(-6645 4800);
DISPLAY 0.638298 (-6645 4800);
PAINT MONO (-6645 4800);
FORCEPROP 1 LAST CDS_LMAN_SYM_OUTLINE -50,50,50,-50
J 0
(-6700 4800);
DISPLAY 0.468085 (-6700 4800);
PAINT GREEN (-6700 4800);
DISPLAY INVISIBLE (-6700 4800);
FORCEPROP 2 LAST CDS_LIB cls
J 0
(-6700 4800);
DISPLAY INVISIBLE (-6700 4800);
FORCEPROP 1 LAST BODY_TYPE COMMENT
J 0
(-6690 4627);
DISPLAY 0.808511 (-6690 4627);
PAINT GREEN (-6690 4627);
DISPLAY INVISIBLE (-6690 4627);
FORCEPROP 1 LAST OFFPAGE TRUE
J 0
(-6690 4707);
DISPLAY 0.808511 (-6690 4707);
PAINT GREEN (-6690 4707);
DISPLAY INVISIBLE (-6690 4707);
FORCEPROP 2 LAST PATH I284
J 0
(-6600 4850);
DISPLAY 1.021277 (-6600 4850);
DISPLAY INVISIBLE (-6600 4850);
FORCEADD OFFPAGE_OUT..1
R 6
(-6700 4900);
FORCEPROP 2 LAST $XR0 26G12> 
J 0
(-6645 4900);
DISPLAY 0.638298 (-6645 4900);
PAINT MONO (-6645 4900);
FORCEPROP 1 LAST CDS_LMAN_SYM_OUTLINE -50,50,50,-50
J 0
(-6700 4900);
DISPLAY 0.468085 (-6700 4900);
PAINT GREEN (-6700 4900);
DISPLAY INVISIBLE (-6700 4900);
FORCEPROP 2 LAST CDS_LIB cls
J 0
(-6700 4900);
DISPLAY INVISIBLE (-6700 4900);
FORCEPROP 1 LAST BODY_TYPE COMMENT
J 0
(-6690 4727);
DISPLAY 0.808511 (-6690 4727);
PAINT GREEN (-6690 4727);
DISPLAY INVISIBLE (-6690 4727);
FORCEPROP 1 LAST OFFPAGE TRUE
J 0
(-6690 4807);
DISPLAY 0.808511 (-6690 4807);
PAINT GREEN (-6690 4807);
DISPLAY INVISIBLE (-6690 4807);
FORCEPROP 2 LAST PATH I285
J 0
(-6600 4950);
DISPLAY 1.021277 (-6600 4950);
DISPLAY INVISIBLE (-6600 4950);
FORCEADD OFFPAGE_OUT..1
R 6
(-6700 4700);
FORCEPROP 2 LAST $XR0 26H12> 
J 0
(-6645 4700);
DISPLAY 0.638298 (-6645 4700);
PAINT MONO (-6645 4700);
FORCEPROP 1 LAST CDS_LMAN_SYM_OUTLINE -50,50,50,-50
J 0
(-6700 4700);
DISPLAY 0.468085 (-6700 4700);
PAINT GREEN (-6700 4700);
DISPLAY INVISIBLE (-6700 4700);
FORCEPROP 2 LAST CDS_LIB cls
J 0
(-6700 4700);
DISPLAY INVISIBLE (-6700 4700);
FORCEPROP 1 LAST BODY_TYPE COMMENT
J 0
(-6690 4527);
DISPLAY 0.808511 (-6690 4527);
PAINT GREEN (-6690 4527);
DISPLAY INVISIBLE (-6690 4527);
FORCEPROP 1 LAST OFFPAGE TRUE
J 0
(-6690 4607);
DISPLAY 0.808511 (-6690 4607);
PAINT GREEN (-6690 4607);
DISPLAY INVISIBLE (-6690 4607);
FORCEPROP 2 LAST PATH I286
J 0
(-6600 4750);
DISPLAY 1.021277 (-6600 4750);
DISPLAY INVISIBLE (-6600 4750);
FORCEADD OFFPAGE_OUT..1
R 6
(-6700 4600);
FORCEPROP 2 LAST $XR0 26H12> 
J 0
(-6645 4600);
DISPLAY 0.638298 (-6645 4600);
PAINT MONO (-6645 4600);
FORCEPROP 1 LAST CDS_LMAN_SYM_OUTLINE -50,50,50,-50
J 0
(-6700 4600);
DISPLAY 0.468085 (-6700 4600);
PAINT GREEN (-6700 4600);
DISPLAY INVISIBLE (-6700 4600);
FORCEPROP 2 LAST CDS_LIB cls
J 0
(-6700 4600);
DISPLAY INVISIBLE (-6700 4600);
FORCEPROP 1 LAST BODY_TYPE COMMENT
J 0
(-6690 4427);
DISPLAY 0.808511 (-6690 4427);
PAINT GREEN (-6690 4427);
DISPLAY INVISIBLE (-6690 4427);
FORCEPROP 1 LAST OFFPAGE TRUE
J 0
(-6690 4507);
DISPLAY 0.808511 (-6690 4507);
PAINT GREEN (-6690 4507);
DISPLAY INVISIBLE (-6690 4507);
FORCEPROP 2 LAST PATH I287
J 0
(-6600 4650);
DISPLAY 1.021277 (-6600 4650);
DISPLAY INVISIBLE (-6600 4650);
FORCEADD RESISTOR..1
(-9250 7050);
FORCEPROP 1 LAST $LOCATION R169
J 2
(-9351 7105);
DISPLAY 1.212766 (-9351 7105);
PAINT GREEN (-9351 7105);
FORCEPROP 0 LAST CDS_LOCATION R169
J 0
(-9100 7200);
DISPLAY 1.021277 (-9100 7200);
DISPLAY INVISIBLE (-9100 7200);
FORCEPROP 0 LAST $SEC 1
J 0
(-9100 7200);
DISPLAY 0.680851 (-9100 7200);
PAINT MONO (-9100 7200);
DISPLAY INVISIBLE (-9100 7200);
FORCEPROP 0 LAST CDS_SEC 1
J 0
(-9100 7200);
DISPLAY 1.021277 (-9100 7200);
DISPLAY INVISIBLE (-9100 7200);
FORCEPROP 0 LASTPIN (-9350 7050) $PN 1
J 2
(-9360 7060);
DISPLAY 0.680851 (-9360 7060);
PAINT MONO (-9360 7060);
FORCEPROP 0 LASTPIN (-9100 7050) $PN 2
J 0
(-9090 7060);
DISPLAY 0.680851 (-9090 7060);
PAINT MONO (-9090 7060);
FORCEPROP 1 LAST VALUE 330OHM
J 0
(-9100 7100);
DISPLAY 1.212766 (-9100 7100);
PAINT GREEN (-9100 7100);
FORCEPROP 0 LAST PACKAGE 0402
J 0
(-9300 6950);
DISPLAY 1.021277 (-9300 6950);
FORCEPROP 2 LAST CDS_LIB passive
J 0
(-9250 7050);
DISPLAY INVISIBLE (-9250 7050);
FORCEPROP 1 LAST PATH I288
J 0
(-9447 7155);
DISPLAY 1.212766 (-9447 7155);
PAINT GREEN (-9447 7155);
DISPLAY INVISIBLE (-9447 7155);
FORCEPROP 1 LAST CDS_LMAN_SYM_OUTLINE -50,50,100,-50
J 0
(-9250 7050);
DISPLAY 0.468085 (-9250 7050);
PAINT GREEN (-9250 7050);
DISPLAY INVISIBLE (-9250 7050);
FORCEPROP 1 LAST TOLERANCE 1%
J 0
(-9447 7305);
DISPLAY 1.212766 (-9447 7305);
PAINT GREEN (-9447 7305);
DISPLAY INVISIBLE (-9447 7305);
FORCEPROP 1 LAST CLS_PN G155-13300-01
J 0
(-9386 7250);
DISPLAY 1.212766 (-9386 7250);
PAINT GREEN (-9386 7250);
DISPLAY INVISIBLE (-9386 7250);
FORCEADD OPTICAL..1
R 2
(-10600 7050);
FORCEPROP 1 LAST $LOCATION DS12
J 0
(-10412 7100);
DISPLAY 1.212766 (-10412 7100);
PAINT GREEN (-10412 7100);
FORCEPROP 0 LAST CDS_LOCATION DS12
J 0
(-11550 7250);
DISPLAY 1.021277 (-11550 7250);
DISPLAY INVISIBLE (-11550 7250);
FORCEPROP 0 LAST $SEC 1
J 0
(-11550 7250);
DISPLAY 0.680851 (-11550 7250);
PAINT MONO (-11550 7250);
DISPLAY INVISIBLE (-11550 7250);
FORCEPROP 0 LAST CDS_SEC 1
J 0
(-11550 7250);
DISPLAY 1.021277 (-11550 7250);
DISPLAY INVISIBLE (-11550 7250);
FORCEPROP 0 LASTPIN (-10350 7050) $PN A
J 0
(-10340 7060);
DISPLAY 0.680851 (-10340 7060);
PAINT MONO (-10340 7060);
FORCEPROP 0 LASTPIN (-10850 7050) $PN C
J 2
(-10860 7060);
DISPLAY 0.680851 (-10860 7060);
PAINT MONO (-10860 7060);
FORCEPROP 0 LAST PART_NUMBER LTST-C190KGKT
J 0
(-11550 7200);
DISPLAY 1.021277 (-11550 7200);
FORCEPROP 1 LAST CLS_PN G170-10143-01
J 2
(-10800 7100);
DISPLAY 1.212766 (-10800 7100);
PAINT GREEN (-10800 7100);
FORCEPROP 2 LASTPIN (-10350 7050) SIG_NAME UN$14$OPTICAL$I289$A
J 0
(-10340 7060);
DISPLAY 0.659574 (-10340 7060);
PAINT MONO (-10340 7060);
DISPLAY INVISIBLE (-10340 7060);
FORCEPROP 2 LAST CDS_LIB discrete
J 0
(-10600 7050);
DISPLAY INVISIBLE (-10600 7050);
FORCEPROP 1 LAST PATH I289
J 2
(-10700 7250);
DISPLAY 1.212766 (-10700 7250);
PAINT GREEN (-10700 7250);
DISPLAY INVISIBLE (-10700 7250);
FORCEPROP 1 LAST CDS_LMAN_SYM_OUTLINE -150,100,150,-50
J 2
(-10600 7050);
DISPLAY 0.468085 (-10600 7050);
PAINT GREEN (-10600 7050);
DISPLAY INVISIBLE (-10600 7050);
FORCEADD VCC..1
(-7850 7150);
FORCEPROP 3 LASTPIN (-7800 7100) SIG_NAME XP3R3V_FT4232\g
J 0
(-7790 7110);
DISPLAY 0.659574 (-7790 7110);
PAINT MONO (-7790 7110);
DISPLAY INVISIBLE (-7790 7110);
FORCEPROP 0 LAST VOLTAGE 3.3V
J 0
(-8100 7250);
DISPLAY 1.021277 (-8100 7250);
DISPLAY BOTH (-8100 7250);
FORCEPROP 1 LAST HDL_POWER XP3R3V_FT4232
J 1
(-7800 7200);
DISPLAY 1.021277 (-7800 7200);
PAINT GREEN (-7800 7200);
FORCEPROP 2 LAST CDS_LIB cls
J 0
(-7850 7150);
DISPLAY INVISIBLE (-7850 7150);
FORCEPROP 1 LAST PATH I290
J 0
(-7815 7240);
DISPLAY 0.808511 (-7815 7240);
PAINT GREEN (-7815 7240);
DISPLAY INVISIBLE (-7815 7240);
FORCEPROP 1 LAST CDS_LMAN_SYM_OUTLINE -250,250,250,-250
J 0
(-7850 7150);
DISPLAY 0.468085 (-7850 7150);
PAINT GREEN (-7850 7150);
DISPLAY INVISIBLE (-7850 7150);
FORCEPROP 1 LAST BODY_TYPE PLUMBING
J 0
(-7895 7107);
DISPLAY 0.340426 (-7895 7107);
PAINT GREEN (-7895 7107);
DISPLAY INVISIBLE (-7895 7107);
FORCEADD OFFPAGE_IN..2
R 2
(-10050 4700);
FORCEPROP 2 LAST $XR0 25D6<> 
J 0
(-10264 4700);
DISPLAY 0.638298 (-10264 4700);
PAINT MONO (-10264 4700);
FORCEPROP 1 LAST OFFPAGE TRUE
J 2
(-10060 4755);
DISPLAY 0.808511 (-10060 4755);
PAINT GREEN (-10060 4755);
DISPLAY INVISIBLE (-10060 4755);
FORCEPROP 1 LAST BODY_TYPE COMMENT
J 2
(-10060 4835);
DISPLAY 0.808511 (-10060 4835);
PAINT GREEN (-10060 4835);
DISPLAY INVISIBLE (-10060 4835);
FORCEPROP 1 LAST CDS_LMAN_SYM_OUTLINE -50,50,50,-50
J 2
(-10050 4700);
DISPLAY 0.468085 (-10050 4700);
PAINT GREEN (-10050 4700);
DISPLAY INVISIBLE (-10050 4700);
FORCEPROP 2 LAST PATH I291
J 0
(-10000 4800);
DISPLAY 1.021277 (-10000 4800);
DISPLAY INVISIBLE (-10000 4800);
FORCEPROP 2 LAST CDS_LIB cls
J 0
(-10050 4700);
DISPLAY INVISIBLE (-10050 4700);
FORCEADD OPTICAL..1
R 2
(-11250 10200);
FORCEPROP 1 LAST LOCATION DS9
J 0
(-10900 10250);
DISPLAY 1.212766 (-10900 10250);
PAINT GREEN (-10900 10250);
FORCEPROP 0 LAST $SEC 1
J 0
(-11200 10150);
DISPLAY 0.680851 (-11200 10150);
PAINT MONO (-11200 10150);
DISPLAY INVISIBLE (-11200 10150);
FORCEPROP 0 LAST CDS_SEC 1
J 0
(-11200 10150);
DISPLAY 1.021277 (-11200 10150);
DISPLAY INVISIBLE (-11200 10150);
FORCEPROP 0 LASTPIN (-11000 10200) $PN A
J 0
(-10990 10210);
DISPLAY 0.680851 (-10990 10210);
PAINT MONO (-10990 10210);
FORCEPROP 0 LASTPIN (-11500 10200) $PN C
J 2
(-11510 10210);
DISPLAY 0.680851 (-11510 10210);
PAINT MONO (-11510 10210);
FORCEPROP 1 LAST CLS_PN G170-10143-01
J 2
(-11450 10250);
DISPLAY 1.212766 (-11450 10250);
PAINT GREEN (-11450 10250);
FORCEPROP 0 LAST PART_NUMBER LTST-C190KGKT
J 0
(-12200 10350);
DISPLAY 1.021277 (-12200 10350);
FORCEPROP 2 LASTPIN (-11000 10200) SIG_NAME UN$14$OPTICAL$I292$A
J 0
(-10990 10210);
DISPLAY 0.659574 (-10990 10210);
PAINT MONO (-10990 10210);
DISPLAY INVISIBLE (-10990 10210);
FORCEPROP 2 LAST CDS_LIB discrete
J 0
(-11250 10200);
DISPLAY INVISIBLE (-11250 10200);
FORCEPROP 1 LAST CDS_LMAN_SYM_OUTLINE -150,100,150,-50
J 2
(-11250 10200);
DISPLAY 0.468085 (-11250 10200);
PAINT GREEN (-11250 10200);
DISPLAY INVISIBLE (-11250 10200);
FORCEPROP 1 LAST PATH I292
J 2
(-11350 10400);
DISPLAY 1.212766 (-11350 10400);
PAINT GREEN (-11350 10400);
DISPLAY INVISIBLE (-11350 10400);
FORCEADD RESISTOR..1
(-10150 10200);
FORCEPROP 1 LAST $LOCATION R208
J 2
(-10300 10200);
DISPLAY 1.212766 (-10300 10200);
PAINT GREEN (-10300 10200);
FORCEPROP 0 LAST CDS_LOCATION R208
J 0
(-9900 10300);
DISPLAY 1.021277 (-9900 10300);
DISPLAY INVISIBLE (-9900 10300);
FORCEPROP 0 LAST $SEC 1
J 0
(-9900 10300);
DISPLAY 0.680851 (-9900 10300);
PAINT MONO (-9900 10300);
DISPLAY INVISIBLE (-9900 10300);
FORCEPROP 0 LAST CDS_SEC 1
J 0
(-9900 10300);
DISPLAY 1.021277 (-9900 10300);
DISPLAY INVISIBLE (-9900 10300);
FORCEPROP 0 LASTPIN (-10250 10200) $PN 1
J 2
(-10260 10210);
DISPLAY 0.680851 (-10260 10210);
PAINT MONO (-10260 10210);
FORCEPROP 0 LASTPIN (-10000 10200) $PN 2
J 0
(-9990 10210);
DISPLAY 0.680851 (-9990 10210);
PAINT MONO (-9990 10210);
FORCEPROP 1 LAST VALUE 330OHM
J 0
(-9911 10205);
DISPLAY 1.212766 (-9911 10205);
PAINT GREEN (-9911 10205);
FORCEPROP 1 LAST PATH I293
J 0
(-10347 10305);
DISPLAY 1.212766 (-10347 10305);
PAINT GREEN (-10347 10305);
DISPLAY INVISIBLE (-10347 10305);
FORCEPROP 1 LAST TOLERANCE 1%
J 0
(-10347 10455);
DISPLAY 1.212766 (-10347 10455);
PAINT GREEN (-10347 10455);
DISPLAY INVISIBLE (-10347 10455);
FORCEPROP 2 LAST CDS_LIB passive
J 0
(-10150 10200);
DISPLAY INVISIBLE (-10150 10200);
FORCEPROP 1 LAST CDS_LMAN_SYM_OUTLINE -50,50,100,-50
J 0
(-10150 10200);
DISPLAY 0.468085 (-10150 10200);
PAINT GREEN (-10150 10200);
DISPLAY INVISIBLE (-10150 10200);
FORCEPROP 1 LAST CLS_PN G155-13300-01
J 0
(-10286 10400);
DISPLAY 1.212766 (-10286 10400);
PAINT GREEN (-10286 10400);
DISPLAY INVISIBLE (-10286 10400);
FORCEADD GND_SG..1
(-12850 10050);
FORCEPROP 3 LASTPIN (-12800 10100) SIG_NAME SG\g
J 0
(-12790 10110);
DISPLAY 0.659574 (-12790 10110);
PAINT MONO (-12790 10110);
DISPLAY INVISIBLE (-12790 10110);
FORCEPROP 1 LAST HDL_POWER SG
J 1
(-12795 9955);
DISPLAY 0.808511 (-12795 9955);
PAINT GREEN (-12795 9955);
FORCEPROP 2 LAST CDS_LIB cls
J 0
(-12850 10050);
DISPLAY INVISIBLE (-12850 10050);
FORCEPROP 1 LAST PATH I294
J 0
(-12815 10050);
DISPLAY 0.808511 (-12815 10050);
PAINT GREEN (-12815 10050);
DISPLAY INVISIBLE (-12815 10050);
FORCEPROP 1 LAST CDS_LMAN_SYM_OUTLINE 0,0,100,-50
J 0
(-12850 10050);
DISPLAY 0.468085 (-12850 10050);
PAINT GREEN (-12850 10050);
DISPLAY INVISIBLE (-12850 10050);
FORCEPROP 1 LAST BODY_TYPE PLUMBING
J 0
(-12835 10035);
DISPLAY 0.808511 (-12835 10035);
PAINT GREEN (-12835 10035);
DISPLAY INVISIBLE (-12835 10035);
FORCEADD OFFPAGE_IN..2
(-8300 10200);
FORCEPROP 2 LAST $XR0 25C9<> 
J 0
(-8245 10200);
DISPLAY 0.638298 (-8245 10200);
PAINT MONO (-8245 10200);
FORCEPROP 2 LAST $XR1 10E12< 
J 0
(-8035 10200);
DISPLAY 0.638298 (-8035 10200);
PAINT MONO (-8035 10200);
FORCEPROP 1 LAST OFFPAGE TRUE
J 0
(-8290 10255);
DISPLAY 0.808511 (-8290 10255);
PAINT GREEN (-8290 10255);
DISPLAY INVISIBLE (-8290 10255);
FORCEPROP 1 LAST BODY_TYPE COMMENT
J 0
(-8290 10335);
DISPLAY 0.808511 (-8290 10335);
PAINT GREEN (-8290 10335);
DISPLAY INVISIBLE (-8290 10335);
FORCEPROP 1 LAST CDS_LMAN_SYM_OUTLINE -50,50,50,-50
J 0
(-8300 10200);
DISPLAY 0.468085 (-8300 10200);
PAINT GREEN (-8300 10200);
DISPLAY INVISIBLE (-8300 10200);
FORCEPROP 2 LAST PATH I295
J 0
(-8250 10300);
DISPLAY 1.021277 (-8250 10300);
DISPLAY INVISIBLE (-8250 10300);
FORCEPROP 2 LAST CDS_LIB cls
J 0
(-8300 10200);
DISPLAY INVISIBLE (-8300 10200);
FORCEADD OFFPAGE_BI..1
R 2
(-13800 5100);
FORCEPROP 2 LAST $XR0 16D4<> 
J 0
(-14019 5100);
DISPLAY 0.638298 (-14019 5100);
PAINT MONO (-14019 5100);
FORCEPROP 2 LAST $XR1 16H3<> 
J 0
(-14229 5100);
DISPLAY 0.638298 (-14229 5100);
PAINT MONO (-14229 5100);
FORCEPROP 1 LAST BODY_TYPE COMMENT
J 2
(-13810 5235);
DISPLAY 0.808511 (-13810 5235);
PAINT GREEN (-13810 5235);
DISPLAY INVISIBLE (-13810 5235);
FORCEPROP 1 LAST CDS_LMAN_SYM_OUTLINE -50,50,50,-50
J 2
(-13800 5100);
DISPLAY 0.468085 (-13800 5100);
PAINT GREEN (-13800 5100);
DISPLAY INVISIBLE (-13800 5100);
FORCEPROP 2 LAST CDS_LIB cls
J 0
(-13800 5100);
PAINT MONO (-13800 5100);
DISPLAY INVISIBLE (-13800 5100);
FORCEPROP 1 LAST OFFPAGE TRUE
J 2
(-13810 5155);
DISPLAY 0.808511 (-13810 5155);
PAINT GREEN (-13810 5155);
DISPLAY INVISIBLE (-13810 5155);
FORCEPROP 2 LAST PATH I296
J 0
(-14000 5150);
DISPLAY 1.021277 (-14000 5150);
DISPLAY INVISIBLE (-14000 5150);
FORCEADD OFFPAGE_IN..2
R 2
(-13800 5000);
FORCEPROP 2 LAST $XR0 16D4> 
J 0
(-13983 5000);
DISPLAY 0.638298 (-13983 5000);
PAINT MONO (-13983 5000);
FORCEPROP 2 LAST $XR1 16H3> 
J 0
(-14163 5000);
DISPLAY 0.638298 (-14163 5000);
PAINT MONO (-14163 5000);
FORCEPROP 2 LAST CDS_LIB cls
J 0
(-13800 5000);
DISPLAY INVISIBLE (-13800 5000);
FORCEPROP 1 LAST CDS_LMAN_SYM_OUTLINE -50,50,50,-50
J 2
(-13800 5000);
DISPLAY 0.468085 (-13800 5000);
PAINT GREEN (-13800 5000);
DISPLAY INVISIBLE (-13800 5000);
FORCEPROP 1 LAST BODY_TYPE COMMENT
J 2
(-13810 5135);
DISPLAY 0.808511 (-13810 5135);
PAINT GREEN (-13810 5135);
DISPLAY INVISIBLE (-13810 5135);
FORCEPROP 1 LAST OFFPAGE TRUE
J 2
(-13810 5055);
DISPLAY 0.808511 (-13810 5055);
PAINT GREEN (-13810 5055);
DISPLAY INVISIBLE (-13810 5055);
FORCEPROP 2 LAST PATH I297
J 0
(-13950 5050);
DISPLAY 1.021277 (-13950 5050);
DISPLAY INVISIBLE (-13950 5050);
FORCEADD RESISTOR..1
(-11900 5100);
FORCEPROP 1 LAST $LOCATION R364
J 2
(-12100 5100);
DISPLAY 1.212766 (-12100 5100);
PAINT GREEN (-12100 5100);
FORCEPROP 0 LAST CDS_LOCATION R364
J 0
(-12100 5200);
DISPLAY 1.021277 (-12100 5200);
DISPLAY INVISIBLE (-12100 5200);
FORCEPROP 0 LAST $SEC 1
J 0
(-12100 5200);
DISPLAY 0.680851 (-12100 5200);
PAINT MONO (-12100 5200);
DISPLAY INVISIBLE (-12100 5200);
FORCEPROP 0 LAST CDS_SEC 1
J 0
(-12100 5200);
DISPLAY 1.021277 (-12100 5200);
DISPLAY INVISIBLE (-12100 5200);
FORCEPROP 0 LASTPIN (-12000 5100) $PN 1
J 2
(-12010 5110);
DISPLAY 0.680851 (-12010 5110);
PAINT MONO (-12010 5110);
FORCEPROP 0 LASTPIN (-11750 5100) $PN 2
J 0
(-11740 5110);
DISPLAY 0.680851 (-11740 5110);
PAINT MONO (-11740 5110);
FORCEPROP 0 LAST PACKAGE 0402
J 0
(-11950 5050);
DISPLAY 0.638298 (-11950 5050);
FORCEPROP 1 LAST VALUE 33OHM
J 0
(-11700 5100);
DISPLAY 0.978723 (-11700 5100);
PAINT GREEN (-11700 5100);
FORCEPROP 1 LAST TOLERANCE 1%
J 0
(-12097 5355);
DISPLAY 1.212766 (-12097 5355);
PAINT GREEN (-12097 5355);
DISPLAY INVISIBLE (-12097 5355);
FORCEPROP 1 LAST CLS_PN G155-133R0-01
J 0
(-12036 5300);
DISPLAY 1.212766 (-12036 5300);
PAINT GREEN (-12036 5300);
DISPLAY INVISIBLE (-12036 5300);
FORCEPROP 2 LAST SIGNAL_MODEL DEFAULT_RESISTOR_33OHM_2_1
J 0
(-12050 5300);
DISPLAY 1.021277 (-12050 5300);
DISPLAY INVISIBLE (-12050 5300);
FORCEPROP 1 LAST CDS_LMAN_SYM_OUTLINE -50,50,100,-50
J 0
(-11900 5100);
DISPLAY 0.468085 (-11900 5100);
PAINT GREEN (-11900 5100);
DISPLAY INVISIBLE (-11900 5100);
FORCEPROP 1 LAST PATH I298
J 0
(-12097 5205);
DISPLAY 1.212766 (-12097 5205);
PAINT GREEN (-12097 5205);
DISPLAY INVISIBLE (-12097 5205);
FORCEPROP 2 LAST CDS_LIB passive
J 0
(-11900 5100);
DISPLAY INVISIBLE (-11900 5100);
FORCEADD RESISTOR..1
(-11900 5000);
FORCEPROP 1 LAST $LOCATION R366
J 2
(-12100 5000);
DISPLAY 1.212766 (-12100 5000);
PAINT GREEN (-12100 5000);
FORCEPROP 0 LAST CDS_LOCATION R366
J 0
(-12100 5100);
DISPLAY 1.021277 (-12100 5100);
DISPLAY INVISIBLE (-12100 5100);
FORCEPROP 0 LAST $SEC 1
J 0
(-12100 5100);
DISPLAY 0.680851 (-12100 5100);
PAINT MONO (-12100 5100);
DISPLAY INVISIBLE (-12100 5100);
FORCEPROP 0 LAST CDS_SEC 1
J 0
(-12100 5100);
DISPLAY 1.021277 (-12100 5100);
DISPLAY INVISIBLE (-12100 5100);
FORCEPROP 0 LASTPIN (-12000 5000) $PN 1
J 2
(-12010 5010);
DISPLAY 0.680851 (-12010 5010);
PAINT MONO (-12010 5010);
FORCEPROP 0 LASTPIN (-11750 5000) $PN 2
J 0
(-11740 5010);
DISPLAY 0.680851 (-11740 5010);
PAINT MONO (-11740 5010);
FORCEPROP 0 LAST PACKAGE 0402
J 0
(-11950 4950);
DISPLAY 0.638298 (-11950 4950);
FORCEPROP 1 LAST VALUE 33OHM
J 0
(-11700 5000);
DISPLAY 0.978723 (-11700 5000);
PAINT GREEN (-11700 5000);
FORCEPROP 1 LAST PATH I299
J 0
(-12097 5105);
DISPLAY 1.212766 (-12097 5105);
PAINT GREEN (-12097 5105);
DISPLAY INVISIBLE (-12097 5105);
FORCEPROP 2 LAST CDS_LIB passive
J 0
(-11900 5000);
DISPLAY INVISIBLE (-11900 5000);
FORCEPROP 1 LAST CDS_LMAN_SYM_OUTLINE -50,50,100,-50
J 0
(-11900 5000);
DISPLAY 0.468085 (-11900 5000);
PAINT GREEN (-11900 5000);
DISPLAY INVISIBLE (-11900 5000);
FORCEPROP 2 LAST SIGNAL_MODEL DEFAULT_RESISTOR_33OHM_2_1
J 0
(-12050 5200);
DISPLAY 1.021277 (-12050 5200);
DISPLAY INVISIBLE (-12050 5200);
FORCEPROP 1 LAST CLS_PN G155-133R0-01
J 0
(-12036 5200);
DISPLAY 1.212766 (-12036 5200);
PAINT GREEN (-12036 5200);
DISPLAY INVISIBLE (-12036 5200);
FORCEPROP 1 LAST TOLERANCE 1%
J 0
(-12097 5255);
DISPLAY 1.212766 (-12097 5255);
PAINT GREEN (-12097 5255);
DISPLAY INVISIBLE (-12097 5255);
FORCEADD OFFPAGE_OUT..2
(-12800 11350);
FORCEPROP 2 LAST $XR0 12E12> 
J 0
(-13014 11350);
DISPLAY 0.638298 (-13014 11350);
PAINT MONO (-13014 11350);
FORCEPROP 2 LAST PATH I3
J 0
(-12950 11400);
DISPLAY 1.021277 (-12950 11400);
DISPLAY INVISIBLE (-12950 11400);
FORCEPROP 1 LAST OFFPAGE TRUE
J 0
(-12790 11405);
DISPLAY 0.808511 (-12790 11405);
PAINT GREEN (-12790 11405);
DISPLAY INVISIBLE (-12790 11405);
FORCEPROP 2 LAST CDS_LIB cls
J 0
(-12800 11350);
DISPLAY INVISIBLE (-12800 11350);
FORCEPROP 1 LAST CDS_LMAN_SYM_OUTLINE -50,50,50,-50
J 0
(-12800 11350);
DISPLAY 0.468085 (-12800 11350);
PAINT GREEN (-12800 11350);
DISPLAY INVISIBLE (-12800 11350);
FORCEPROP 1 LAST BODY_TYPE COMMENT
J 0
(-12790 11485);
DISPLAY 0.808511 (-12790 11485);
PAINT GREEN (-12790 11485);
DISPLAY INVISIBLE (-12790 11485);
FORCEADD VCC..1
(-7850 8600);
FORCEPROP 3 LASTPIN (-7800 8550) SIG_NAME XP5R0V\g
J 0
(-7790 8560);
DISPLAY 0.659574 (-7790 8560);
PAINT MONO (-7790 8560);
DISPLAY INVISIBLE (-7790 8560);
FORCEPROP 1 LAST HDL_POWER XP5R0V
J 1
(-7800 8650);
DISPLAY 1.021277 (-7800 8650);
PAINT GREEN (-7800 8650);
FORCEPROP 0 LAST VOLTAGE 5.0V
J 0
(-8100 8700);
DISPLAY 1.021277 (-8100 8700);
DISPLAY BOTH (-8100 8700);
FORCEPROP 1 LAST PATH I39
J 0
(-7815 8690);
DISPLAY 0.808511 (-7815 8690);
PAINT GREEN (-7815 8690);
DISPLAY INVISIBLE (-7815 8690);
FORCEPROP 1 LAST BODY_TYPE PLUMBING
J 0
(-7895 8557);
DISPLAY 0.340426 (-7895 8557);
PAINT GREEN (-7895 8557);
DISPLAY INVISIBLE (-7895 8557);
FORCEPROP 1 LAST CDS_LMAN_SYM_OUTLINE -250,250,250,-250
J 0
(-7850 8600);
DISPLAY 0.468085 (-7850 8600);
PAINT GREEN (-7850 8600);
DISPLAY INVISIBLE (-7850 8600);
FORCEPROP 2 LAST CDS_LIB cls
J 0
(-7850 8600);
DISPLAY INVISIBLE (-7850 8600);
FORCEADD RESISTOR..1
(-9150 8500);
FORCEPROP 1 LAST $LOCATION R180
J 2
(-9350 8550);
DISPLAY 1.212766 (-9350 8550);
PAINT GREEN (-9350 8550);
FORCEPROP 0 LAST CDS_LOCATION R180
J 0
(-8900 8600);
DISPLAY 1.021277 (-8900 8600);
DISPLAY INVISIBLE (-8900 8600);
FORCEPROP 0 LAST $SEC 1
J 0
(-8900 8600);
DISPLAY 0.680851 (-8900 8600);
PAINT MONO (-8900 8600);
DISPLAY INVISIBLE (-8900 8600);
FORCEPROP 0 LAST CDS_SEC 1
J 0
(-8900 8600);
DISPLAY 1.021277 (-8900 8600);
DISPLAY INVISIBLE (-8900 8600);
FORCEPROP 0 LASTPIN (-9250 8500) $PN 1
J 2
(-9260 8510);
DISPLAY 0.680851 (-9260 8510);
PAINT MONO (-9260 8510);
FORCEPROP 0 LASTPIN (-9000 8500) $PN 2
J 0
(-8990 8510);
DISPLAY 0.680851 (-8990 8510);
PAINT MONO (-8990 8510);
FORCEPROP 0 LAST PACKAGE 0402
J 0
(-9200 8400);
DISPLAY 1.021277 (-9200 8400);
FORCEPROP 1 LAST VALUE 1KOHM
J 0
(-8950 8550);
DISPLAY 1.212766 (-8950 8550);
PAINT GREEN (-8950 8550);
FORCEPROP 1 LAST PATH I44
J 0
(-9347 8605);
DISPLAY 1.212766 (-9347 8605);
PAINT GREEN (-9347 8605);
DISPLAY INVISIBLE (-9347 8605);
FORCEPROP 1 LAST TOLERANCE 1%
J 0
(-9347 8755);
DISPLAY 1.212766 (-9347 8755);
PAINT GREEN (-9347 8755);
DISPLAY INVISIBLE (-9347 8755);
FORCEPROP 2 LAST CDS_LIB passive
J 0
(-9150 8500);
DISPLAY INVISIBLE (-9150 8500);
FORCEPROP 1 LAST CDS_LMAN_SYM_OUTLINE -50,50,100,-50
J 0
(-9150 8500);
DISPLAY 0.468085 (-9150 8500);
PAINT GREEN (-9150 8500);
DISPLAY INVISIBLE (-9150 8500);
FORCEPROP 1 LAST CLS_PN G155-11001-01
J 0
(-9286 8700);
DISPLAY 1.212766 (-9286 8700);
PAINT GREEN (-9286 8700);
DISPLAY INVISIBLE (-9286 8700);
FORCEADD VCC..1
(-7850 8200);
FORCEPROP 3 LASTPIN (-7800 8150) SIG_NAME XP12R0V\g
J 0
(-7790 8160);
DISPLAY 0.659574 (-7790 8160);
PAINT MONO (-7790 8160);
DISPLAY INVISIBLE (-7790 8160);
FORCEPROP 1 LAST HDL_POWER XP12R0V
J 1
(-7795 8255);
DISPLAY 0.808511 (-7795 8255);
PAINT GREEN (-7795 8255);
FORCEPROP 0 LAST VOLTAGE 12V
J 0
(-8050 8300);
DISPLAY 1.021277 (-8050 8300);
DISPLAY BOTH (-8050 8300);
FORCEPROP 2 LAST CDS_LIB cls
J 0
(-7850 8200);
DISPLAY INVISIBLE (-7850 8200);
FORCEPROP 1 LAST CDS_LMAN_SYM_OUTLINE -250,250,250,-250
J 0
(-7850 8200);
DISPLAY 0.468085 (-7850 8200);
PAINT GREEN (-7850 8200);
DISPLAY INVISIBLE (-7850 8200);
FORCEPROP 1 LAST BODY_TYPE PLUMBING
J 0
(-7895 8157);
DISPLAY 0.340426 (-7895 8157);
PAINT GREEN (-7895 8157);
DISPLAY INVISIBLE (-7895 8157);
FORCEPROP 1 LAST PATH I50
J 0
(-7815 8290);
DISPLAY 0.808511 (-7815 8290);
PAINT GREEN (-7815 8290);
DISPLAY INVISIBLE (-7815 8290);
FORCEADD GND_SG..1
(-12300 6900);
FORCEPROP 3 LASTPIN (-12250 6950) SIG_NAME SG\g
J 0
(-12240 6960);
DISPLAY 0.659574 (-12240 6960);
PAINT MONO (-12240 6960);
DISPLAY INVISIBLE (-12240 6960);
FORCEPROP 1 LAST HDL_POWER SG
J 1
(-12245 6805);
DISPLAY 0.808511 (-12245 6805);
PAINT GREEN (-12245 6805);
FORCEPROP 1 LAST CDS_LMAN_SYM_OUTLINE 0,0,100,-50
J 0
(-12300 6900);
DISPLAY 0.468085 (-12300 6900);
PAINT GREEN (-12300 6900);
DISPLAY INVISIBLE (-12300 6900);
FORCEPROP 2 LAST CDS_LIB cls
J 0
(-12300 6900);
DISPLAY INVISIBLE (-12300 6900);
FORCEPROP 1 LAST PATH I51
J 0
(-12265 6900);
DISPLAY 0.808511 (-12265 6900);
PAINT GREEN (-12265 6900);
DISPLAY INVISIBLE (-12265 6900);
FORCEPROP 1 LAST BODY_TYPE PLUMBING
J 0
(-12285 6885);
DISPLAY 0.808511 (-12285 6885);
PAINT GREEN (-12285 6885);
DISPLAY INVISIBLE (-12285 6885);
FORCEADD VCC..1
(-7750 12550);
FORCEPROP 3 LASTPIN (-7700 12500) SIG_NAME XP3R3V_FPGA\g
J 0
(-7690 12510);
DISPLAY 0.659574 (-7690 12510);
PAINT MONO (-7690 12510);
DISPLAY INVISIBLE (-7690 12510);
FORCEPROP 0 LAST VOLTAGE 3.3V
J 0
(-8000 12700);
DISPLAY 1.021277 (-8000 12700);
DISPLAY BOTH (-8000 12700);
FORCEPROP 1 LAST HDL_POWER XP3R3V_FPGA
J 1
(-7695 12605);
DISPLAY 1.021277 (-7695 12605);
PAINT GREEN (-7695 12605);
FORCEPROP 1 LAST PATH I57
J 0
(-7715 12640);
DISPLAY 0.808511 (-7715 12640);
PAINT GREEN (-7715 12640);
DISPLAY INVISIBLE (-7715 12640);
FORCEPROP 1 LAST BODY_TYPE PLUMBING
J 0
(-7795 12507);
DISPLAY 0.340426 (-7795 12507);
PAINT GREEN (-7795 12507);
DISPLAY INVISIBLE (-7795 12507);
FORCEPROP 1 LAST CDS_LMAN_SYM_OUTLINE -250,250,250,-250
J 0
(-7750 12550);
DISPLAY 0.468085 (-7750 12550);
PAINT GREEN (-7750 12550);
DISPLAY INVISIBLE (-7750 12550);
FORCEPROP 2 LAST CDS_LIB cls
J 0
(-7750 12550);
DISPLAY INVISIBLE (-7750 12550);
FORCEADD RESISTOR..1
(-9600 8850);
FORCEPROP 1 LAST $LOCATION R108
J 2
(-9750 8900);
DISPLAY 1.212766 (-9750 8900);
PAINT GREEN (-9750 8900);
FORCEPROP 0 LAST CDS_LOCATION R108
J 0
(-9500 9000);
DISPLAY 1.021277 (-9500 9000);
DISPLAY INVISIBLE (-9500 9000);
FORCEPROP 0 LAST $SEC 1
J 0
(-9500 9000);
DISPLAY 0.680851 (-9500 9000);
PAINT MONO (-9500 9000);
DISPLAY INVISIBLE (-9500 9000);
FORCEPROP 0 LAST CDS_SEC 1
J 0
(-9500 9000);
DISPLAY 1.021277 (-9500 9000);
DISPLAY INVISIBLE (-9500 9000);
FORCEPROP 0 LASTPIN (-9700 8850) $PN 1
J 2
(-9710 8860);
DISPLAY 0.680851 (-9710 8860);
PAINT MONO (-9710 8860);
FORCEPROP 0 LASTPIN (-9450 8850) $PN 2
J 0
(-9440 8860);
DISPLAY 0.680851 (-9440 8860);
PAINT MONO (-9440 8860);
FORCEPROP 1 LAST VALUE 100OHM
J 0
(-9400 8900);
DISPLAY 1.212766 (-9400 8900);
PAINT GREEN (-9400 8900);
FORCEPROP 0 LAST PACKAGE 0402
J 0
(-9650 8750);
DISPLAY 1.021277 (-9650 8750);
FORCEPROP 1 LAST PATH I58
J 0
(-9797 8955);
DISPLAY 1.212766 (-9797 8955);
PAINT GREEN (-9797 8955);
DISPLAY INVISIBLE (-9797 8955);
FORCEPROP 1 LAST TOLERANCE 1%
J 0
(-9797 9105);
DISPLAY 1.212766 (-9797 9105);
PAINT GREEN (-9797 9105);
DISPLAY INVISIBLE (-9797 9105);
FORCEPROP 2 LASTPIN (-9450 8850) SIG_NAME UN$14$RESISTOR$I58$2
J 0
(-9440 8860);
DISPLAY 0.659574 (-9440 8860);
PAINT MONO (-9440 8860);
DISPLAY INVISIBLE (-9440 8860);
FORCEPROP 2 LAST CDS_LIB passive
J 0
(-9600 8850);
DISPLAY INVISIBLE (-9600 8850);
FORCEPROP 1 LAST CDS_LMAN_SYM_OUTLINE -50,50,100,-50
J 0
(-9600 8850);
DISPLAY 0.468085 (-9600 8850);
PAINT GREEN (-9600 8850);
DISPLAY INVISIBLE (-9600 8850);
FORCEPROP 1 LAST CLS_PN G155-11000-01
J 0
(-9736 9050);
DISPLAY 1.212766 (-9736 9050);
PAINT GREEN (-9736 9050);
DISPLAY INVISIBLE (-9736 9050);
FORCEADD VCC..1
(-7850 8950);
FORCEPROP 3 LASTPIN (-7800 8900) SIG_NAME XP2R5V_FPGA\g
J 0
(-7790 8910);
DISPLAY 0.659574 (-7790 8910);
PAINT MONO (-7790 8910);
DISPLAY INVISIBLE (-7790 8910);
FORCEPROP 0 LAST VOLTAGE 2.5V
J 0
(-7950 9100);
DISPLAY 1.021277 (-7950 9100);
DISPLAY BOTH (-7950 9100);
FORCEPROP 1 LAST HDL_POWER XP2R5V_FPGA
J 1
(-7795 9005);
DISPLAY 1.021277 (-7795 9005);
PAINT GREEN (-7795 9005);
FORCEPROP 1 LAST CDS_LMAN_SYM_OUTLINE -250,250,250,-250
J 0
(-7850 8950);
DISPLAY 0.468085 (-7850 8950);
PAINT GREEN (-7850 8950);
DISPLAY INVISIBLE (-7850 8950);
FORCEPROP 2 LAST CDS_LIB cls
J 0
(-7850 8950);
DISPLAY INVISIBLE (-7850 8950);
FORCEPROP 1 LAST BODY_TYPE PLUMBING
J 0
(-7895 8907);
DISPLAY 0.340426 (-7895 8907);
PAINT GREEN (-7895 8907);
DISPLAY INVISIBLE (-7895 8907);
FORCEPROP 1 LAST PATH I59
J 0
(-7815 9040);
DISPLAY 0.808511 (-7815 9040);
PAINT GREEN (-7815 9040);
DISPLAY INVISIBLE (-7815 9040);
FORCEADD RESISTOR..1
(-8650 8850);
FORCEPROP 1 LAST $LOCATION R139
J 2
(-8800 8900);
DISPLAY 1.212766 (-8800 8900);
PAINT GREEN (-8800 8900);
FORCEPROP 0 LAST CDS_LOCATION R139
J 0
(-8550 9000);
DISPLAY 1.021277 (-8550 9000);
DISPLAY INVISIBLE (-8550 9000);
FORCEPROP 0 LAST $SEC 1
J 0
(-8550 9000);
DISPLAY 0.680851 (-8550 9000);
PAINT MONO (-8550 9000);
DISPLAY INVISIBLE (-8550 9000);
FORCEPROP 0 LAST CDS_SEC 1
J 0
(-8550 9000);
DISPLAY 1.021277 (-8550 9000);
DISPLAY INVISIBLE (-8550 9000);
FORCEPROP 0 LASTPIN (-8750 8850) $PN 1
J 2
(-8760 8860);
DISPLAY 0.680851 (-8760 8860);
PAINT MONO (-8760 8860);
FORCEPROP 0 LASTPIN (-8500 8850) $PN 2
J 0
(-8490 8860);
DISPLAY 0.680851 (-8490 8860);
PAINT MONO (-8490 8860);
FORCEPROP 1 LAST VALUE 33OHM
J 0
(-8500 8900);
DISPLAY 1.212766 (-8500 8900);
PAINT GREEN (-8500 8900);
FORCEPROP 0 LAST PACKAGE 0402
J 0
(-8700 8750);
DISPLAY 1.021277 (-8700 8750);
FORCEPROP 1 LAST PATH I60
J 0
(-8847 8955);
DISPLAY 1.212766 (-8847 8955);
PAINT GREEN (-8847 8955);
DISPLAY INVISIBLE (-8847 8955);
FORCEPROP 1 LAST TOLERANCE 1%
J 0
(-8847 9105);
DISPLAY 1.212766 (-8847 9105);
PAINT GREEN (-8847 9105);
DISPLAY INVISIBLE (-8847 9105);
FORCEPROP 1 LAST CLS_PN G155-133R0-01
J 0
(-8786 9050);
DISPLAY 1.212766 (-8786 9050);
PAINT GREEN (-8786 9050);
DISPLAY INVISIBLE (-8786 9050);
FORCEPROP 1 LAST CDS_LMAN_SYM_OUTLINE -50,50,100,-50
J 0
(-8650 8850);
DISPLAY 0.468085 (-8650 8850);
PAINT GREEN (-8650 8850);
DISPLAY INVISIBLE (-8650 8850);
FORCEPROP 2 LAST CDS_LIB passive
J 0
(-8650 8850);
DISPLAY INVISIBLE (-8650 8850);
FORCEADD VCC..1
(-7850 9300);
FORCEPROP 3 LASTPIN (-7800 9250) SIG_NAME XP3R3V_FPGA\g
J 0
(-7790 9260);
DISPLAY 0.659574 (-7790 9260);
PAINT MONO (-7790 9260);
DISPLAY INVISIBLE (-7790 9260);
FORCEPROP 1 LAST HDL_POWER XP3R3V_FPGA
J 1
(-7795 9355);
DISPLAY 1.021277 (-7795 9355);
PAINT GREEN (-7795 9355);
FORCEPROP 0 LAST VOLTAGE 3.3V
J 0
(-8100 9450);
DISPLAY 1.021277 (-8100 9450);
DISPLAY BOTH (-8100 9450);
FORCEPROP 1 LAST PATH I62
J 0
(-7815 9390);
DISPLAY 0.808511 (-7815 9390);
PAINT GREEN (-7815 9390);
DISPLAY INVISIBLE (-7815 9390);
FORCEPROP 1 LAST BODY_TYPE PLUMBING
J 0
(-7895 9257);
DISPLAY 0.340426 (-7895 9257);
PAINT GREEN (-7895 9257);
DISPLAY INVISIBLE (-7895 9257);
FORCEPROP 2 LAST CDS_LIB cls
J 0
(-7850 9300);
DISPLAY INVISIBLE (-7850 9300);
FORCEPROP 1 LAST CDS_LMAN_SYM_OUTLINE -250,250,250,-250
J 0
(-7850 9300);
DISPLAY 0.468085 (-7850 9300);
PAINT GREEN (-7850 9300);
DISPLAY INVISIBLE (-7850 9300);
FORCEADD RESISTOR..1
(-9250 9200);
FORCEPROP 1 LAST $LOCATION R138
J 2
(-9400 9250);
DISPLAY 1.212766 (-9400 9250);
PAINT GREEN (-9400 9250);
FORCEPROP 0 LAST CDS_LOCATION R138
J 0
(-9350 9350);
DISPLAY 1.021277 (-9350 9350);
DISPLAY INVISIBLE (-9350 9350);
FORCEPROP 0 LAST $SEC 1
J 0
(-9350 9350);
DISPLAY 0.680851 (-9350 9350);
PAINT MONO (-9350 9350);
DISPLAY INVISIBLE (-9350 9350);
FORCEPROP 0 LAST CDS_SEC 1
J 0
(-9350 9350);
DISPLAY 1.021277 (-9350 9350);
DISPLAY INVISIBLE (-9350 9350);
FORCEPROP 0 LASTPIN (-9350 9200) $PN 1
J 2
(-9360 9210);
DISPLAY 0.680851 (-9360 9210);
PAINT MONO (-9360 9210);
FORCEPROP 0 LASTPIN (-9100 9200) $PN 2
J 0
(-9090 9210);
DISPLAY 0.680851 (-9090 9210);
PAINT MONO (-9090 9210);
FORCEPROP 0 LAST PACKAGE 0402
J 0
(-9300 9100);
DISPLAY 1.021277 (-9300 9100);
FORCEPROP 1 LAST VALUE 330OHM
J 0
(-9100 9250);
DISPLAY 1.212766 (-9100 9250);
PAINT GREEN (-9100 9250);
FORCEPROP 1 LAST PATH I63
J 0
(-9447 9305);
DISPLAY 1.212766 (-9447 9305);
PAINT GREEN (-9447 9305);
DISPLAY INVISIBLE (-9447 9305);
FORCEPROP 1 LAST TOLERANCE 1%
J 0
(-9447 9455);
DISPLAY 1.212766 (-9447 9455);
PAINT GREEN (-9447 9455);
DISPLAY INVISIBLE (-9447 9455);
FORCEPROP 1 LAST CLS_PN G155-13300-01
J 0
(-9386 9400);
DISPLAY 1.212766 (-9386 9400);
PAINT GREEN (-9386 9400);
DISPLAY INVISIBLE (-9386 9400);
FORCEPROP 2 LAST CDS_LIB passive
J 0
(-9250 9200);
DISPLAY INVISIBLE (-9250 9200);
FORCEPROP 1 LAST CDS_LMAN_SYM_OUTLINE -50,50,100,-50
J 0
(-9250 9200);
DISPLAY 0.468085 (-9250 9200);
PAINT GREEN (-9250 9200);
DISPLAY INVISIBLE (-9250 9200);
FORCEADD RESISTOR..1
(-9650 8100);
FORCEPROP 1 LAST $LOCATION R256
J 2
(-9750 8150);
DISPLAY 1.212766 (-9750 8150);
PAINT GREEN (-9750 8150);
FORCEPROP 0 LAST CDS_LOCATION R256
J 0
(-9550 8250);
DISPLAY 1.021277 (-9550 8250);
DISPLAY INVISIBLE (-9550 8250);
FORCEPROP 0 LAST $SEC 1
J 0
(-9550 8250);
DISPLAY 0.680851 (-9550 8250);
PAINT MONO (-9550 8250);
DISPLAY INVISIBLE (-9550 8250);
FORCEPROP 0 LAST CDS_SEC 1
J 0
(-9550 8250);
DISPLAY 1.021277 (-9550 8250);
DISPLAY INVISIBLE (-9550 8250);
FORCEPROP 0 LASTPIN (-9750 8100) $PN 1
J 2
(-9760 8110);
DISPLAY 0.680851 (-9760 8110);
PAINT MONO (-9760 8110);
FORCEPROP 0 LASTPIN (-9500 8100) $PN 2
J 0
(-9490 8110);
DISPLAY 0.680851 (-9490 8110);
PAINT MONO (-9490 8110);
FORCEPROP 1 LAST VALUE 1KOHM
J 0
(-9550 8150);
DISPLAY 1.212766 (-9550 8150);
PAINT GREEN (-9550 8150);
FORCEPROP 0 LAST PACKAGE 0402
J 0
(-9700 8000);
DISPLAY 1.021277 (-9700 8000);
FORCEPROP 1 LAST PATH I65
J 0
(-9847 8205);
DISPLAY 1.212766 (-9847 8205);
PAINT GREEN (-9847 8205);
DISPLAY INVISIBLE (-9847 8205);
FORCEPROP 1 LAST TOLERANCE 1%
J 0
(-9847 8355);
DISPLAY 1.212766 (-9847 8355);
PAINT GREEN (-9847 8355);
DISPLAY INVISIBLE (-9847 8355);
FORCEPROP 1 LAST CLS_PN G155-11001-01
J 0
(-9786 8300);
DISPLAY 1.212766 (-9786 8300);
PAINT GREEN (-9786 8300);
DISPLAY INVISIBLE (-9786 8300);
FORCEPROP 1 LAST CDS_LMAN_SYM_OUTLINE -50,50,100,-50
J 0
(-9650 8100);
DISPLAY 0.468085 (-9650 8100);
PAINT GREEN (-9650 8100);
DISPLAY INVISIBLE (-9650 8100);
FORCEPROP 2 LAST CDS_LIB passive
J 0
(-9650 8100);
DISPLAY INVISIBLE (-9650 8100);
FORCEPROP 2 LASTPIN (-9500 8100) SIG_NAME UN$14$RESISTOR$I65$2
J 0
(-9490 8110);
DISPLAY 0.659574 (-9490 8110);
PAINT MONO (-9490 8110);
DISPLAY INVISIBLE (-9490 8110);
FORCEADD RESISTOR..1
(-8750 8100);
FORCEPROP 1 LAST $LOCATION R262
J 2
(-8850 8150);
DISPLAY 1.212766 (-8850 8150);
PAINT GREEN (-8850 8150);
FORCEPROP 0 LAST CDS_LOCATION R262
J 0
(-8650 8250);
DISPLAY 1.021277 (-8650 8250);
DISPLAY INVISIBLE (-8650 8250);
FORCEPROP 0 LAST $SEC 1
J 0
(-8650 8250);
DISPLAY 0.680851 (-8650 8250);
PAINT MONO (-8650 8250);
DISPLAY INVISIBLE (-8650 8250);
FORCEPROP 0 LAST CDS_SEC 1
J 0
(-8650 8250);
DISPLAY 1.021277 (-8650 8250);
DISPLAY INVISIBLE (-8650 8250);
FORCEPROP 0 LASTPIN (-8850 8100) $PN 1
J 2
(-8860 8110);
DISPLAY 0.680851 (-8860 8110);
PAINT MONO (-8860 8110);
FORCEPROP 0 LASTPIN (-8600 8100) $PN 2
J 0
(-8590 8110);
DISPLAY 0.680851 (-8590 8110);
PAINT MONO (-8590 8110);
FORCEPROP 0 LAST PACKAGE 0402
J 0
(-8800 8000);
DISPLAY 1.021277 (-8800 8000);
FORCEPROP 1 LAST VALUE 1KOHM
J 0
(-8650 8150);
DISPLAY 1.212766 (-8650 8150);
PAINT GREEN (-8650 8150);
FORCEPROP 1 LAST PATH I66
J 0
(-8947 8205);
DISPLAY 1.212766 (-8947 8205);
PAINT GREEN (-8947 8205);
DISPLAY INVISIBLE (-8947 8205);
FORCEPROP 1 LAST TOLERANCE 1%
J 0
(-8947 8355);
DISPLAY 1.212766 (-8947 8355);
PAINT GREEN (-8947 8355);
DISPLAY INVISIBLE (-8947 8355);
FORCEPROP 2 LAST CDS_LIB passive
J 0
(-8750 8100);
DISPLAY INVISIBLE (-8750 8100);
FORCEPROP 1 LAST CDS_LMAN_SYM_OUTLINE -50,50,100,-50
J 0
(-8750 8100);
DISPLAY 0.468085 (-8750 8100);
PAINT GREEN (-8750 8100);
DISPLAY INVISIBLE (-8750 8100);
FORCEPROP 1 LAST CLS_PN G155-11001-01
J 0
(-8886 8300);
DISPLAY 1.212766 (-8886 8300);
PAINT GREEN (-8886 8300);
DISPLAY INVISIBLE (-8886 8300);
FORCEADD RESISTOR..1
(-8900 12400);
FORCEPROP 1 LAST $LOCATION R257
J 2
(-9100 12450);
DISPLAY 1.212766 (-9100 12450);
PAINT GREEN (-9100 12450);
FORCEPROP 0 LAST CDS_LOCATION R257
J 0
(-8750 12550);
DISPLAY 1.021277 (-8750 12550);
DISPLAY INVISIBLE (-8750 12550);
FORCEPROP 0 LAST $SEC 1
J 0
(-8750 12550);
DISPLAY 0.680851 (-8750 12550);
PAINT MONO (-8750 12550);
DISPLAY INVISIBLE (-8750 12550);
FORCEPROP 0 LAST CDS_SEC 1
J 0
(-8750 12550);
DISPLAY 1.021277 (-8750 12550);
DISPLAY INVISIBLE (-8750 12550);
FORCEPROP 0 LASTPIN (-9000 12400) $PN 1
J 2
(-9010 12410);
DISPLAY 0.680851 (-9010 12410);
PAINT MONO (-9010 12410);
FORCEPROP 0 LASTPIN (-8750 12400) $PN 2
J 0
(-8740 12410);
DISPLAY 0.680851 (-8740 12410);
PAINT MONO (-8740 12410);
FORCEPROP 1 LAST VALUE 330OHM
J 0
(-8700 12450);
DISPLAY 1.212766 (-8700 12450);
PAINT GREEN (-8700 12450);
FORCEPROP 0 LAST PACKAGE 0402
J 0
(-8950 12450);
DISPLAY 1.021277 (-8950 12450);
FORCEPROP 1 LAST CLS_PN G155-13300-01
J 0
(-9036 12600);
DISPLAY 1.212766 (-9036 12600);
PAINT GREEN (-9036 12600);
DISPLAY INVISIBLE (-9036 12600);
FORCEPROP 1 LAST CDS_LMAN_SYM_OUTLINE -50,50,100,-50
J 0
(-8900 12400);
DISPLAY 0.468085 (-8900 12400);
PAINT GREEN (-8900 12400);
DISPLAY INVISIBLE (-8900 12400);
FORCEPROP 2 LAST CDS_LIB passive
J 0
(-8900 12400);
DISPLAY INVISIBLE (-8900 12400);
FORCEPROP 1 LAST TOLERANCE 1%
J 0
(-9097 12655);
DISPLAY 1.212766 (-9097 12655);
PAINT GREEN (-9097 12655);
DISPLAY INVISIBLE (-9097 12655);
FORCEPROP 1 LAST PATH I67
J 0
(-9097 12505);
DISPLAY 1.212766 (-9097 12505);
PAINT GREEN (-9097 12505);
DISPLAY INVISIBLE (-9097 12505);
FORCEADD RESISTOR..1
(-8900 12050);
FORCEPROP 1 LAST $LOCATION R258
J 2
(-9100 12100);
DISPLAY 1.212766 (-9100 12100);
PAINT GREEN (-9100 12100);
FORCEPROP 0 LAST CDS_LOCATION R258
J 0
(-8750 12200);
DISPLAY 1.021277 (-8750 12200);
DISPLAY INVISIBLE (-8750 12200);
FORCEPROP 0 LAST $SEC 1
J 0
(-8750 12200);
DISPLAY 0.680851 (-8750 12200);
PAINT MONO (-8750 12200);
DISPLAY INVISIBLE (-8750 12200);
FORCEPROP 0 LAST CDS_SEC 1
J 0
(-8750 12200);
DISPLAY 1.021277 (-8750 12200);
DISPLAY INVISIBLE (-8750 12200);
FORCEPROP 0 LASTPIN (-9000 12050) $PN 1
J 2
(-9010 12060);
DISPLAY 0.680851 (-9010 12060);
PAINT MONO (-9010 12060);
FORCEPROP 0 LASTPIN (-8750 12050) $PN 2
J 0
(-8740 12060);
DISPLAY 0.680851 (-8740 12060);
PAINT MONO (-8740 12060);
FORCEPROP 1 LAST VALUE 330OHM
J 0
(-8700 12100);
DISPLAY 1.212766 (-8700 12100);
PAINT GREEN (-8700 12100);
FORCEPROP 0 LAST PACKAGE 0402
J 0
(-8950 12100);
DISPLAY 1.021277 (-8950 12100);
FORCEPROP 1 LAST CLS_PN G155-13300-01
J 0
(-9036 12250);
DISPLAY 1.212766 (-9036 12250);
PAINT GREEN (-9036 12250);
DISPLAY INVISIBLE (-9036 12250);
FORCEPROP 1 LAST CDS_LMAN_SYM_OUTLINE -50,50,100,-50
J 0
(-8900 12050);
DISPLAY 0.468085 (-8900 12050);
PAINT GREEN (-8900 12050);
DISPLAY INVISIBLE (-8900 12050);
FORCEPROP 2 LAST CDS_LIB passive
J 0
(-8900 12050);
DISPLAY INVISIBLE (-8900 12050);
FORCEPROP 1 LAST TOLERANCE 1%
J 0
(-9097 12305);
DISPLAY 1.212766 (-9097 12305);
PAINT GREEN (-9097 12305);
DISPLAY INVISIBLE (-9097 12305);
FORCEPROP 1 LAST PATH I68
J 0
(-9097 12155);
DISPLAY 1.212766 (-9097 12155);
PAINT GREEN (-9097 12155);
DISPLAY INVISIBLE (-9097 12155);
FORCEADD RESISTOR..1
(-8900 11700);
FORCEPROP 1 LAST $LOCATION R259
J 2
(-9100 11750);
DISPLAY 1.212766 (-9100 11750);
PAINT GREEN (-9100 11750);
FORCEPROP 0 LAST CDS_LOCATION R259
J 0
(-8750 11850);
DISPLAY 1.021277 (-8750 11850);
DISPLAY INVISIBLE (-8750 11850);
FORCEPROP 0 LAST $SEC 1
J 0
(-8750 11850);
DISPLAY 0.680851 (-8750 11850);
PAINT MONO (-8750 11850);
DISPLAY INVISIBLE (-8750 11850);
FORCEPROP 0 LAST CDS_SEC 1
J 0
(-8750 11850);
DISPLAY 1.021277 (-8750 11850);
DISPLAY INVISIBLE (-8750 11850);
FORCEPROP 0 LASTPIN (-9000 11700) $PN 1
J 2
(-9010 11710);
DISPLAY 0.680851 (-9010 11710);
PAINT MONO (-9010 11710);
FORCEPROP 0 LASTPIN (-8750 11700) $PN 2
J 0
(-8740 11710);
DISPLAY 0.680851 (-8740 11710);
PAINT MONO (-8740 11710);
FORCEPROP 1 LAST VALUE 330OHM
J 0
(-8700 11750);
DISPLAY 1.212766 (-8700 11750);
PAINT GREEN (-8700 11750);
FORCEPROP 0 LAST PACKAGE 0402
J 0
(-8950 11750);
DISPLAY 1.021277 (-8950 11750);
FORCEPROP 1 LAST CLS_PN G155-13300-01
J 0
(-9036 11900);
DISPLAY 1.212766 (-9036 11900);
PAINT GREEN (-9036 11900);
DISPLAY INVISIBLE (-9036 11900);
FORCEPROP 1 LAST CDS_LMAN_SYM_OUTLINE -50,50,100,-50
J 0
(-8900 11700);
DISPLAY 0.468085 (-8900 11700);
PAINT GREEN (-8900 11700);
DISPLAY INVISIBLE (-8900 11700);
FORCEPROP 2 LAST CDS_LIB passive
J 0
(-8900 11700);
DISPLAY INVISIBLE (-8900 11700);
FORCEPROP 1 LAST TOLERANCE 1%
J 0
(-9097 11955);
DISPLAY 1.212766 (-9097 11955);
PAINT GREEN (-9097 11955);
DISPLAY INVISIBLE (-9097 11955);
FORCEPROP 1 LAST PATH I69
J 0
(-9097 11805);
DISPLAY 1.212766 (-9097 11805);
PAINT GREEN (-9097 11805);
DISPLAY INVISIBLE (-9097 11805);
FORCEADD OFFPAGE_OUT..2
(-12800 11700);
FORCEPROP 2 LAST $XR0 12E12> 
J 0
(-13014 11700);
DISPLAY 0.638298 (-13014 11700);
PAINT MONO (-13014 11700);
FORCEPROP 2 LAST PATH I7
J 0
(-12950 11750);
DISPLAY 1.021277 (-12950 11750);
DISPLAY INVISIBLE (-12950 11750);
FORCEPROP 1 LAST OFFPAGE TRUE
J 0
(-12790 11755);
DISPLAY 0.808511 (-12790 11755);
PAINT GREEN (-12790 11755);
DISPLAY INVISIBLE (-12790 11755);
FORCEPROP 1 LAST BODY_TYPE COMMENT
J 0
(-12790 11835);
DISPLAY 0.808511 (-12790 11835);
PAINT GREEN (-12790 11835);
DISPLAY INVISIBLE (-12790 11835);
FORCEPROP 1 LAST CDS_LMAN_SYM_OUTLINE -50,50,50,-50
J 0
(-12800 11700);
DISPLAY 0.468085 (-12800 11700);
PAINT GREEN (-12800 11700);
DISPLAY INVISIBLE (-12800 11700);
FORCEPROP 2 LAST CDS_LIB cls
J 0
(-12800 11700);
DISPLAY INVISIBLE (-12800 11700);
FORCEADD RESISTOR..1
(-8900 11350);
FORCEPROP 1 LAST $LOCATION R261
J 2
(-9100 11400);
DISPLAY 1.212766 (-9100 11400);
PAINT GREEN (-9100 11400);
FORCEPROP 0 LAST CDS_LOCATION R261
J 0
(-8750 11500);
DISPLAY 1.021277 (-8750 11500);
DISPLAY INVISIBLE (-8750 11500);
FORCEPROP 0 LAST $SEC 1
J 0
(-8750 11500);
DISPLAY 0.680851 (-8750 11500);
PAINT MONO (-8750 11500);
DISPLAY INVISIBLE (-8750 11500);
FORCEPROP 0 LAST CDS_SEC 1
J 0
(-8750 11500);
DISPLAY 1.021277 (-8750 11500);
DISPLAY INVISIBLE (-8750 11500);
FORCEPROP 0 LASTPIN (-9000 11350) $PN 1
J 2
(-9010 11360);
DISPLAY 0.680851 (-9010 11360);
PAINT MONO (-9010 11360);
FORCEPROP 0 LASTPIN (-8750 11350) $PN 2
J 0
(-8740 11360);
DISPLAY 0.680851 (-8740 11360);
PAINT MONO (-8740 11360);
FORCEPROP 0 LAST PACKAGE 0402
J 0
(-8950 11400);
DISPLAY 1.021277 (-8950 11400);
FORCEPROP 1 LAST VALUE 330OHM
J 0
(-8700 11400);
DISPLAY 1.212766 (-8700 11400);
PAINT GREEN (-8700 11400);
FORCEPROP 1 LAST CLS_PN G155-13300-01
J 0
(-9036 11550);
DISPLAY 1.212766 (-9036 11550);
PAINT GREEN (-9036 11550);
DISPLAY INVISIBLE (-9036 11550);
FORCEPROP 2 LAST CDS_LIB passive
J 0
(-8900 11350);
DISPLAY INVISIBLE (-8900 11350);
FORCEPROP 1 LAST CDS_LMAN_SYM_OUTLINE -50,50,100,-50
J 0
(-8900 11350);
DISPLAY 0.468085 (-8900 11350);
PAINT GREEN (-8900 11350);
DISPLAY INVISIBLE (-8900 11350);
FORCEPROP 1 LAST TOLERANCE 1%
J 0
(-9097 11605);
DISPLAY 1.212766 (-9097 11605);
PAINT GREEN (-9097 11605);
DISPLAY INVISIBLE (-9097 11605);
FORCEPROP 1 LAST PATH I70
J 0
(-9097 11455);
DISPLAY 1.212766 (-9097 11455);
PAINT GREEN (-9097 11455);
DISPLAY INVISIBLE (-9097 11455);
FORCEADD RESISTOR..1
(-8900 10950);
FORCEPROP 1 LAST $LOCATION R279
J 2
(-9100 11000);
DISPLAY 1.212766 (-9100 11000);
PAINT GREEN (-9100 11000);
FORCEPROP 0 LAST CDS_LOCATION R279
J 0
(-8700 11100);
DISPLAY 1.021277 (-8700 11100);
DISPLAY INVISIBLE (-8700 11100);
FORCEPROP 0 LAST $SEC 1
J 0
(-8700 11100);
DISPLAY 0.680851 (-8700 11100);
PAINT MONO (-8700 11100);
DISPLAY INVISIBLE (-8700 11100);
FORCEPROP 0 LAST CDS_SEC 1
J 0
(-8700 11100);
DISPLAY 1.021277 (-8700 11100);
DISPLAY INVISIBLE (-8700 11100);
FORCEPROP 0 LASTPIN (-9000 10950) $PN 1
J 2
(-9010 10960);
DISPLAY 0.680851 (-9010 10960);
PAINT MONO (-9010 10960);
FORCEPROP 0 LASTPIN (-8750 10950) $PN 2
J 0
(-8740 10960);
DISPLAY 0.680851 (-8740 10960);
PAINT MONO (-8740 10960);
FORCEPROP 1 LAST VALUE 330OHM
J 0
(-8700 11000);
DISPLAY 1.212766 (-8700 11000);
PAINT GREEN (-8700 11000);
FORCEPROP 0 LAST PACKAGE 0402
J 0
(-8950 11000);
DISPLAY 1.021277 (-8950 11000);
FORCEPROP 1 LAST PATH I72
J 0
(-9097 11055);
DISPLAY 1.212766 (-9097 11055);
PAINT GREEN (-9097 11055);
DISPLAY INVISIBLE (-9097 11055);
FORCEPROP 1 LAST TOLERANCE 1%
J 0
(-9097 11205);
DISPLAY 1.212766 (-9097 11205);
PAINT GREEN (-9097 11205);
DISPLAY INVISIBLE (-9097 11205);
FORCEPROP 2 LAST CDS_LIB passive
J 0
(-8900 10950);
DISPLAY INVISIBLE (-8900 10950);
FORCEPROP 1 LAST CDS_LMAN_SYM_OUTLINE -50,50,100,-50
J 0
(-8900 10950);
DISPLAY 0.468085 (-8900 10950);
PAINT GREEN (-8900 10950);
DISPLAY INVISIBLE (-8900 10950);
FORCEPROP 1 LAST CLS_PN G155-13300-01
J 0
(-9036 11150);
DISPLAY 1.212766 (-9036 11150);
PAINT GREEN (-9036 11150);
DISPLAY INVISIBLE (-9036 11150);
FORCEADD OFFPAGE_OUT..2
(-12800 10950);
FORCEPROP 2 LAST $XR0 12E12> 
J 0
(-13014 10950);
DISPLAY 0.638298 (-13014 10950);
PAINT MONO (-13014 10950);
FORCEPROP 2 LAST CDS_LIB cls
J 0
(-12800 10950);
DISPLAY INVISIBLE (-12800 10950);
FORCEPROP 1 LAST CDS_LMAN_SYM_OUTLINE -50,50,50,-50
J 0
(-12800 10950);
DISPLAY 0.468085 (-12800 10950);
PAINT GREEN (-12800 10950);
DISPLAY INVISIBLE (-12800 10950);
FORCEPROP 1 LAST BODY_TYPE COMMENT
J 0
(-12790 11085);
DISPLAY 0.808511 (-12790 11085);
PAINT GREEN (-12790 11085);
DISPLAY INVISIBLE (-12790 11085);
FORCEPROP 1 LAST OFFPAGE TRUE
J 0
(-12790 11005);
DISPLAY 0.808511 (-12790 11005);
PAINT GREEN (-12790 11005);
DISPLAY INVISIBLE (-12790 11005);
FORCEPROP 2 LAST PATH I73
J 0
(-12750 11050);
DISPLAY 1.021277 (-12750 11050);
DISPLAY INVISIBLE (-12750 11050);
FORCEADD RESISTOR..1
(-8900 10650);
FORCEPROP 1 LAST $LOCATION R280
J 2
(-9100 10700);
DISPLAY 1.212766 (-9100 10700);
PAINT GREEN (-9100 10700);
FORCEPROP 0 LAST CDS_LOCATION R280
J 0
(-8700 10800);
DISPLAY 1.021277 (-8700 10800);
DISPLAY INVISIBLE (-8700 10800);
FORCEPROP 0 LAST $SEC 1
J 0
(-8700 10800);
DISPLAY 0.680851 (-8700 10800);
PAINT MONO (-8700 10800);
DISPLAY INVISIBLE (-8700 10800);
FORCEPROP 0 LAST CDS_SEC 1
J 0
(-8700 10800);
DISPLAY 1.021277 (-8700 10800);
DISPLAY INVISIBLE (-8700 10800);
FORCEPROP 0 LASTPIN (-9000 10650) $PN 1
J 2
(-9010 10660);
DISPLAY 0.680851 (-9010 10660);
PAINT MONO (-9010 10660);
FORCEPROP 0 LASTPIN (-8750 10650) $PN 2
J 0
(-8740 10660);
DISPLAY 0.680851 (-8740 10660);
PAINT MONO (-8740 10660);
FORCEPROP 1 LAST VALUE 330OHM
J 0
(-8700 10700);
DISPLAY 1.212766 (-8700 10700);
PAINT GREEN (-8700 10700);
FORCEPROP 0 LAST PACKAGE 0402
J 0
(-8950 10700);
DISPLAY 1.021277 (-8950 10700);
FORCEPROP 1 LAST PATH I74
J 0
(-9097 10755);
DISPLAY 1.212766 (-9097 10755);
PAINT GREEN (-9097 10755);
DISPLAY INVISIBLE (-9097 10755);
FORCEPROP 1 LAST TOLERANCE 1%
J 0
(-9097 10905);
DISPLAY 1.212766 (-9097 10905);
PAINT GREEN (-9097 10905);
DISPLAY INVISIBLE (-9097 10905);
FORCEPROP 1 LAST CLS_PN G155-13300-01
J 0
(-9036 10850);
DISPLAY 1.212766 (-9036 10850);
PAINT GREEN (-9036 10850);
DISPLAY INVISIBLE (-9036 10850);
FORCEPROP 1 LAST CDS_LMAN_SYM_OUTLINE -50,50,100,-50
J 0
(-8900 10650);
DISPLAY 0.468085 (-8900 10650);
PAINT GREEN (-8900 10650);
DISPLAY INVISIBLE (-8900 10650);
FORCEPROP 2 LAST CDS_LIB passive
J 0
(-8900 10650);
DISPLAY INVISIBLE (-8900 10650);
FORCEADD OFFPAGE_OUT..2
(-12800 10650);
FORCEPROP 2 LAST $XR0 12F12> 
J 0
(-13014 10650);
DISPLAY 0.638298 (-13014 10650);
PAINT MONO (-13014 10650);
FORCEPROP 1 LAST BODY_TYPE COMMENT
J 0
(-12790 10785);
DISPLAY 0.808511 (-12790 10785);
PAINT GREEN (-12790 10785);
DISPLAY INVISIBLE (-12790 10785);
FORCEPROP 1 LAST CDS_LMAN_SYM_OUTLINE -50,50,50,-50
J 0
(-12800 10650);
DISPLAY 0.468085 (-12800 10650);
PAINT GREEN (-12800 10650);
DISPLAY INVISIBLE (-12800 10650);
FORCEPROP 2 LAST CDS_LIB cls
J 0
(-12800 10650);
DISPLAY INVISIBLE (-12800 10650);
FORCEPROP 1 LAST OFFPAGE TRUE
J 0
(-12790 10705);
DISPLAY 0.808511 (-12790 10705);
PAINT GREEN (-12790 10705);
DISPLAY INVISIBLE (-12790 10705);
FORCEPROP 2 LAST PATH I76
J 0
(-12750 10750);
DISPLAY 1.021277 (-12750 10750);
DISPLAY INVISIBLE (-12750 10750);
FORCEADD OFFPAGE_OUT..2
(-12800 12050);
FORCEPROP 2 LAST $XR0 12E12> 
J 0
(-13014 12050);
DISPLAY 0.638298 (-13014 12050);
PAINT MONO (-13014 12050);
FORCEPROP 2 LAST PATH I8
J 0
(-12950 12100);
DISPLAY 1.021277 (-12950 12100);
DISPLAY INVISIBLE (-12950 12100);
FORCEPROP 1 LAST OFFPAGE TRUE
J 0
(-12790 12105);
DISPLAY 0.808511 (-12790 12105);
PAINT GREEN (-12790 12105);
DISPLAY INVISIBLE (-12790 12105);
FORCEPROP 1 LAST BODY_TYPE COMMENT
J 0
(-12790 12185);
DISPLAY 0.808511 (-12790 12185);
PAINT GREEN (-12790 12185);
DISPLAY INVISIBLE (-12790 12185);
FORCEPROP 1 LAST CDS_LMAN_SYM_OUTLINE -50,50,50,-50
J 0
(-12800 12050);
DISPLAY 0.468085 (-12800 12050);
PAINT GREEN (-12800 12050);
DISPLAY INVISIBLE (-12800 12050);
FORCEPROP 2 LAST CDS_LIB cls
J 0
(-12800 12050);
DISPLAY INVISIBLE (-12800 12050);
FORCEADD OFFPAGE_OUT..1
R 4
(-4550 11050);
FORCEPROP 2 LAST $XR0 26J9> 
J 0
(-4733 11050);
DISPLAY 0.638298 (-4733 11050);
PAINT MONO (-4733 11050);
FORCEPROP 2 LAST CDS_LIB cls
J 0
(-4550 11050);
DISPLAY INVISIBLE (-4550 11050);
FORCEPROP 1 LAST CDS_LMAN_SYM_OUTLINE -50,50,50,-50
R 2
J 0
(-4550 11050);
DISPLAY 0.468085 (-4550 11050);
PAINT GREEN (-4550 11050);
DISPLAY INVISIBLE (-4550 11050);
FORCEPROP 1 LAST BODY_TYPE COMMENT
R 2
J 0
(-4560 10915);
DISPLAY 0.808511 (-4560 10915);
PAINT GREEN (-4560 10915);
DISPLAY INVISIBLE (-4560 10915);
FORCEPROP 1 LAST OFFPAGE TRUE
R 2
J 0
(-4560 10995);
DISPLAY 0.808511 (-4560 10995);
PAINT GREEN (-4560 10995);
DISPLAY INVISIBLE (-4560 10995);
FORCEPROP 2 LAST PATH I87
J 0
(-4500 11150);
DISPLAY 1.021277 (-4500 11150);
DISPLAY INVISIBLE (-4500 11150);
FORCEADD OFFPAGE_OUT..1
R 4
(-4550 11350);
FORCEPROP 2 LAST $XR0 26J9> 
J 0
(-4733 11350);
DISPLAY 0.638298 (-4733 11350);
PAINT MONO (-4733 11350);
FORCEPROP 2 LAST CDS_LIB cls
J 0
(-4550 11350);
DISPLAY INVISIBLE (-4550 11350);
FORCEPROP 1 LAST CDS_LMAN_SYM_OUTLINE -50,50,50,-50
R 2
J 0
(-4550 11350);
DISPLAY 0.468085 (-4550 11350);
PAINT GREEN (-4550 11350);
DISPLAY INVISIBLE (-4550 11350);
FORCEPROP 1 LAST BODY_TYPE COMMENT
R 2
J 0
(-4560 11215);
DISPLAY 0.808511 (-4560 11215);
PAINT GREEN (-4560 11215);
DISPLAY INVISIBLE (-4560 11215);
FORCEPROP 1 LAST OFFPAGE TRUE
R 2
J 0
(-4560 11295);
DISPLAY 0.808511 (-4560 11295);
PAINT GREEN (-4560 11295);
DISPLAY INVISIBLE (-4560 11295);
FORCEPROP 2 LAST PATH I88
J 0
(-4500 11450);
DISPLAY 1.021277 (-4500 11450);
DISPLAY INVISIBLE (-4500 11450);
FORCEADD OFFPAGE_OUT..2
(-12800 12400);
FORCEPROP 2 LAST $XR0 12E12> 
J 0
(-13014 12400);
DISPLAY 0.638298 (-13014 12400);
PAINT MONO (-13014 12400);
FORCEPROP 2 LAST PATH I9
J 0
(-12950 12450);
DISPLAY 1.021277 (-12950 12450);
DISPLAY INVISIBLE (-12950 12450);
FORCEPROP 1 LAST OFFPAGE TRUE
J 0
(-12790 12455);
DISPLAY 0.808511 (-12790 12455);
PAINT GREEN (-12790 12455);
DISPLAY INVISIBLE (-12790 12455);
FORCEPROP 1 LAST BODY_TYPE COMMENT
J 0
(-12790 12535);
DISPLAY 0.808511 (-12790 12535);
PAINT GREEN (-12790 12535);
DISPLAY INVISIBLE (-12790 12535);
FORCEPROP 1 LAST CDS_LMAN_SYM_OUTLINE -50,50,50,-50
J 0
(-12800 12400);
DISPLAY 0.468085 (-12800 12400);
PAINT GREEN (-12800 12400);
DISPLAY INVISIBLE (-12800 12400);
FORCEPROP 2 LAST CDS_LIB cls
J 0
(-12800 12400);
DISPLAY INVISIBLE (-12800 12400);
FORCEADD SHEET_A1..1
(250 2600);
FORCEPROP 2 LAST CUSTOM_TXT_CDS <XR_PAGE_TITLE>
J 0
(-15320 13950);
DISPLAY 0.638298 (-15320 13950);
PAINT PINK (-15320 13950);
FORCEPROP 1 LAST CUSTOM_TXT_CDS <DOCNO>
J 0
(-1800 2985);
DISPLAY 0.978723 (-1800 2985);
FORCEPROP 1 LAST CUSTOM_TXT_CDS <CON_PAGE_NUM>
J 0
(-1905 2650);
DISPLAY 0.978723 (-1905 2650);
FORCEPROP 1 LAST CUSTOM_TXT_CDS <DATE>
J 0
(-450 2775);
DISPLAY 0.978723 (-450 2775);
FORCEPROP 1 LAST CUSTOM_TXT_CDS <TITLE>
J 1
(-1535 3230);
DISPLAY 0.978723 (-1535 3230);
FORCEPROP 1 LAST CUSTOM_TXT_CDS <DESIGNER>
J 0
(-450 3200);
DISPLAY 0.978723 (-450 3200);
FORCEPROP 1 LAST CUSTOM_TXT_CDS <CON_TOTAL_PAGES>
J 0
(-1595 2650);
DISPLAY 0.808511 (-1595 2650);
FORCEPROP 1 LAST CUSTOM_TXT_CDS <ASSY_PN>
J 0
(-1800 2775);
DISPLAY 0.978723 (-1800 2775);
FORCEPROP 1 LAST CUSTOM_TXT_CDS <DOCREV>
J 0
(-450 2975);
DISPLAY 0.978723 (-450 2975);
FORCEPROP 1 LAST TITLE LED_INDICATOR
J 0
(-2250 3450);
DISPLAY 3.042553 (-2250 3450);
PAINT GREEN (-2250 3450);
FORCEPROP 2 LAST CDS_LIB cls
J 0
(250 2600);
DISPLAY INVISIBLE (250 2600);
FORCEPROP 1 LAST CDS_LMAN_SYM_OUTLINE -15850,11500,200,-200
J 0
(250 2600);
DISPLAY 0.468085 (250 2600);
PAINT GREEN (250 2600);
DISPLAY INVISIBLE (250 2600);
FORCEPROP 2 LAST PAGE_BORDER TRUE
J 0
(-15320 13950);
DISPLAY 0.638298 (-15320 13950);
PAINT PINK (-15320 13950);
DISPLAY INVISIBLE (-15320 13950);
FORCEPROP 1 LAST COMMENT_BODY TRUE
J 0
(260 2655);
DISPLAY 0.808511 (260 2655);
DISPLAY INVISIBLE (260 2655);
FORCEPROP 2 LAST CDS_XR_PAGE_TITLE CR-26 : @TIMECARD_LIB.TIMECARD(SCH_1):PAGE26
J 0
(-15320 13950);
DISPLAY 0.638298 (-15320 13950);
PAINT PINK (-15320 13950);
DISPLAY INVISIBLE (-15320 13950);
WIRE 16 -1 (-7800 9200)(-7800 9250);
WIRE 16 -1 (-9100 9200)(-7800 9200);
WIRE 16 -1 (-7800 8850)(-7800 8900);
WIRE 16 -1 (-7800 8850)(-8500 8850);
WIRE 16 -1 (-7800 8500)(-7800 8550);
WIRE 16 -1 (-7800 8500)(-9000 8500);
WIRE 16 -1 (-9750 4450)(-9750 4400);
WIRE 16 -1 (-7800 7750)(-7800 7800);
WIRE 16 -1 (-9100 7750)(-7800 7750);
WIRE 16 -1 (-7800 7400)(-7800 7450);
WIRE 16 -1 (-9100 7400)(-7800 7400);
WIRE 16 -1 (-8750 10650)(-7700 10650);
WIRE 16 -1 (-7700 10950)(-7700 10650);
WIRE 16 -1 (-8750 10950)(-7700 10950);
WIRE 16 -1 (-7700 11350)(-7700 10950);
WIRE 16 -1 (-8750 11350)(-7700 11350);
WIRE 16 -1 (-7700 11350)(-7700 11700);
WIRE 16 -1 (-8750 11700)(-7700 11700);
WIRE 16 -1 (-7700 11700)(-7700 12050);
WIRE 16 -1 (-7700 12050)(-7700 12400);
WIRE 16 -1 (-8750 12050)(-7700 12050);
WIRE 16 -1 (-7700 12400)(-7700 12500);
WIRE 16 -1 (-8750 12400)(-7700 12400);
WIRE 16 -1 (-12250 9200)(-10850 9200);
WIRE 16 -1 (-12250 9200)(-12250 8850);
WIRE 16 -1 (-12250 8850)(-10850 8850);
WIRE 16 -1 (-12250 8500)(-12250 8850);
WIRE 16 -1 (-10850 8500)(-12250 8500);
WIRE 16 -1 (-12250 8100)(-12250 8500);
WIRE 16 -1 (-10850 8100)(-12250 8100);
WIRE 16 -1 (-12250 7750)(-12250 8100);
WIRE 16 -1 (-12250 7750)(-10850 7750);
WIRE 16 -1 (-12250 7400)(-12250 7750);
WIRE 16 -1 (-12250 7400)(-10850 7400);
WIRE 16 -1 (-12250 7050)(-12250 7400);
WIRE 16 -1 (-12250 6950)(-12250 7050);
WIRE 16 -1 (-12250 7050)(-10850 7050);
WIRE 16 -1 (-7800 8150)(-7800 8100);
WIRE 16 -1 (-8600 8100)(-7800 8100);
WIRE 16 -1 (-12800 10100)(-12800 10200);
WIRE 16 -1 (-12800 10200)(-11500 10200);
WIRE 16 -1 (-7800 7100)(-7800 7050);
WIRE 16 -1 (-9100 7050)(-7800 7050);
WIRE 16 -1 (-10050 3450)(-9600 3450);
WIRE 16 -1 (-10050 3600)(-10050 3450);
WIRE 16 -1 (-10050 3450)(-10050 3400);
WIRE 16 -1 (-9600 3600)(-9600 3450);
WIRE 16 -1 (-10550 5650)(-10150 5650);
WIRE 16 -1 (-10550 5650)(-10550 5750);
WIRE 16 -1 (-10150 5650)(-10150 5750);
WIRE 16 -1 (-10150 5600)(-10150 5650);
WIRE 16 -1 (-9400 5600)(-9400 6150);
WIRE 16 -1 (-9400 5600)(-9300 5600);
WIRE 16 -1 (-9400 6150)(-9700 6150);
WIRE 16 -1 (-9700 5600)(-9700 6150);
WIRE 16 -1 (-10150 6150)(-9700 6150);
WIRE 16 -1 (-10150 6000)(-10150 6150);
WIRE 16 -1 (-10550 6150)(-10150 6150);
WIRE 16 -1 (-10550 6000)(-10550 6150);
WIRE 16 -1 (-11000 6150)(-10550 6150);
WIRE 16 -1 (-11000 5950)(-11000 6150);
WIRE 16 -1 (-11400 6150)(-11000 6150);
WIRE 16 -1 (-11700 6150)(-11400 6150);
WIRE 16 -1 (-11400 5950)(-11400 6150);
WIRE 16 -1 (-11700 6150)(-11700 6250);
WIRE 16 -1 (-8150 3400)(-8150 3200);
WIRE 16 -1 (-8350 3400)(-8150 3400);
WIRE 16 -1 (-8150 3500)(-8150 3400);
WIRE 16 -1 (-8150 3200)(-8150 3100);
WIRE 16 -1 (-8350 3200)(-8150 3200);
WIRE 16 -1 (-8350 3500)(-8150 3500);
WIRE 16 -1 (-8150 3600)(-8150 3500);
WIRE 16 -1 (-8150 3700)(-8150 3600);
WIRE 16 -1 (-8350 3600)(-8150 3600);
WIRE 16 -1 (-8350 3700)(-8150 3700);
WIRE 16 -1 (-450 4900)(-450 6450);
WIRE 16 -1 (-450 4900)(-1100 4900);
WIRE 16 -1 (-450 6450)(-450 8000);
WIRE 16 -1 (-450 6450)(-1100 6450);
WIRE 16 -1 (-1100 8000)(-450 8000);
WIRE 16 -1 (-450 8000)(-450 9550);
WIRE 16 -1 (-450 9550)(-450 11050);
WIRE 16 -1 (-1100 9550)(-450 9550);
WIRE 16 -1 (-450 12000)(-450 11050);
WIRE 16 -1 (-1100 11050)(-450 11050);
WIRE 16 -1 (-8350 5300)(-6750 5300);
FORCEPROP 2 LAST SIG_NAME SMA2_LED_GREEN_N
J 0
(-7710 5310);
DISPLAY 1.021277 (-7710 5310);
WIRE 16 -1 (-8350 4700)(-6750 4700);
FORCEPROP 2 LAST SIG_NAME SMA4_LED_GREEN_N
J 0
(-7710 4710);
DISPLAY 1.021277 (-7710 4710);
WIRE 16 -1 (-6750 4200)(-8350 4200);
FORCEPROP 2 LAST SIG_NAME GPS_SMA_LED_BLUE_N
J 0
(-7710 4210);
DISPLAY 1.021277 (-7710 4210);
WIRE 16 -1 (-8350 4300)(-6750 4300);
FORCEPROP 2 LAST SIG_NAME GPS_SMA_LED_RED_N
J 0
(-7710 4310);
DISPLAY 1.021277 (-7710 4310);
WIRE 16 -1 (-9300 4800)(-9700 4800);
WIRE 16 -1 (-9700 5350)(-9700 4800);
WIRE 16 -1 (-9700 4800)(-9750 4800);
WIRE 16 -1 (-9750 4700)(-9750 4800);
WIRE 16 -1 (-9950 4800)(-9750 4800);
WIRE 16 -1 (-9950 4800)(-9950 4700);
WIRE 16 -1 (-11750 4800)(-9950 4800);
FORCEPROP 2 LAST SIG_NAME RGB_LED_SHUTDOWN_N
J 0
(-11210 4810);
DISPLAY 1.021277 (-11210 4810);
WIRE 16 -1 (-9950 4700)(-10000 4700);
WIRE 16 -1 (-8350 5200)(-6750 5200);
FORCEPROP 2 LAST SIG_NAME SMA2_LED_RED_N
J 0
(-7710 5210);
DISPLAY 1.021277 (-7710 5210);
WIRE 16 -1 (-11750 5300)(-11400 5300);
WIRE 16 -1 (-11400 5300)(-10750 5300);
WIRE 16 -1 (-11400 5700)(-11400 5300);
WIRE 16 -1 (-10750 5300)(-10750 5100);
WIRE 16 -1 (-11750 5100)(-10750 5100);
WIRE 16 -1 (-9300 5100)(-10750 5100);
FORCEPROP 2 LAST SIG_NAME R_RGB_LED_I2C_SDA
J 0
(-10610 5110);
DISPLAY 1.021277 (-10610 5110);
WIRE 16 -1 (-11750 5200)(-11000 5200);
WIRE 16 -1 (-11000 5700)(-11000 5200);
WIRE 16 -1 (-11000 5200)(-10850 5200);
WIRE 16 -1 (-10850 5200)(-10850 5000);
WIRE 16 -1 (-11750 5000)(-10850 5000);
WIRE 16 -1 (-9300 5000)(-10850 5000);
FORCEPROP 2 LAST SIG_NAME R_RGB_LED_I2C_SCL
J 0
(-10610 5010);
DISPLAY 1.021277 (-10610 5010);
WIRE 16 -1 (-8350 5600)(-6750 5600);
FORCEPROP 2 LAST SIG_NAME SMA1_LED_GREEN_N
J 0
(-7710 5610);
DISPLAY 1.021277 (-7710 5610);
WIRE 16 -1 (-6750 5400)(-8350 5400);
FORCEPROP 2 LAST SIG_NAME SMA1_LED_BLUE_N
J 0
(-7710 5410);
DISPLAY 1.021277 (-7710 5410);
WIRE 16 -1 (-6750 5100)(-8350 5100);
FORCEPROP 2 LAST SIG_NAME SMA2_LED_BLUE_N
J 0
(-7710 5110);
DISPLAY 1.021277 (-7710 5110);
WIRE 16 -1 (-8350 5000)(-6750 5000);
FORCEPROP 2 LAST SIG_NAME SMA3_LED_GREEN_N
J 0
(-7710 5010);
DISPLAY 1.021277 (-7710 5010);
WIRE 16 -1 (-6750 4800)(-8350 4800);
FORCEPROP 2 LAST SIG_NAME SMA3_LED_BLUE_N
J 0
(-7710 4810);
DISPLAY 1.021277 (-7710 4810);
WIRE 16 -1 (-8350 4900)(-6750 4900);
FORCEPROP 2 LAST SIG_NAME SMA3_LED_RED_N
J 0
(-7710 4910);
DISPLAY 1.021277 (-7710 4910);
WIRE 16 273 (-14300 6650)(-5550 6650);
WIRE 16 273 (-5550 9850)(-5550 6650);
WIRE 16 273 (-5550 6650)(-5550 3100);
WIRE 16 273 (-5550 12600)(-5550 9850);
WIRE 16 273 (-5550 9850)(-14300 9850);
WIRE 16 -1 (-13750 5300)(-12000 5300);
FORCEPROP 2 LAST SIG_NAME FPGA_M_RGB_LED_I2C_SDA
J 0
(-13710 5310);
DISPLAY 1.021277 (-13710 5310);
WIRE 16 -1 (-13750 5200)(-12000 5200);
FORCEPROP 2 LAST SIG_NAME FPGA_M_RGB_LED_I2C_SCL
J 0
(-13710 5210);
DISPLAY 1.021277 (-13710 5210);
WIRE 16 -1 (-13750 5100)(-12000 5100);
FORCEPROP 2 LAST SIG_NAME RGB_LED_I2C_SDA
J 0
(-13710 5110);
DISPLAY 1.021277 (-13710 5110);
WIRE 16 -1 (-13750 5000)(-12000 5000);
FORCEPROP 2 LAST SIG_NAME RGB_LED_I2C_SCL
J 0
(-13710 5010);
DISPLAY 1.021277 (-13710 5010);
WIRE 16 -1 (-8350 5500)(-6750 5500);
FORCEPROP 2 LAST SIG_NAME SMA1_LED_RED_N
J 0
(-7710 5510);
DISPLAY 1.021277 (-7710 5510);
WIRE 16 -1 (-10750 11700)(-12750 11700);
FORCEPROP 2 LAST SIG_NAME LED_DATOUT1
J 0
(-12660 11710);
DISPLAY 1.021277 (-12660 11710);
WIRE 16 -1 (-10750 11350)(-12750 11350);
FORCEPROP 2 LAST SIG_NAME LED_DATOUT0
J 0
(-12660 11360);
DISPLAY 1.021277 (-12660 11360);
WIRE 16 -1 (-12000 4800)(-13750 4800);
FORCEPROP 2 LAST SIG_NAME FPGA_OUT_RGB_LED_SHUTDOWN_N
J 0
(-13710 4810);
DISPLAY 1.021277 (-13710 4810);
WIRE 16 -1 (-9300 4200)(-10050 4200);
WIRE 16 -1 (-10050 4200)(-10050 3850);
WIRE 16 -1 (-4500 6750)(-2900 6750);
FORCEPROP 2 LAST SIG_NAME SMA4_LED_GREEN_N
J 0
(-4460 6760);
DISPLAY 1.021277 (-4460 6760);
WIRE 16 -1 (-4450 4600)(-2850 4600);
FORCEPROP 2 LAST SIG_NAME GPS_SMA_LED_BLUE_N
J 0
(-4410 4610);
DISPLAY 1.021277 (-4410 4610);
WIRE 16 -1 (-8350 4400)(-6750 4400);
FORCEPROP 2 LAST SIG_NAME GPS_SMA_LED_GREEN_N
J 0
(-7710 4410);
DISPLAY 1.021277 (-7710 4410);
WIRE 16 -1 (-4500 7850)(-2900 7850);
FORCEPROP 2 LAST SIG_NAME FPGA_OUT_SMA3_LED_RED_N
J 0
(-4460 7860);
DISPLAY 1.021277 (-4460 7860);
WIRE 16 -1 (-4500 6300)(-2900 6300);
FORCEPROP 2 LAST SIG_NAME FPGA_OUT_SMA4_LED_RED_N
J 0
(-4460 6310);
DISPLAY 1.021277 (-4460 6310);
WIRE 16 -1 (-4500 6000)(-2900 6000);
FORCEPROP 2 LAST SIG_NAME FPGA_OUT_SMA4_LED_BLUE_N
J 0
(-4460 6010);
DISPLAY 1.021277 (-4460 6010);
WIRE 16 -1 (-4500 9850)(-2900 9850);
FORCEPROP 2 LAST SIG_NAME SMA2_LED_GREEN_N
J 0
(-4460 9860);
DISPLAY 1.021277 (-4460 9860);
WIRE 16 -1 (-4500 9700)(-2900 9700);
FORCEPROP 2 LAST SIG_NAME FPGA_OUT_SMA2_LED_GREEN_N
J 0
(-4460 9710);
DISPLAY 1.021277 (-4460 9710);
WIRE 16 -1 (-4450 5050)(-2850 5050);
FORCEPROP 2 LAST SIG_NAME FPGA_OUT_GPS_LED_GREEN_N
J 0
(-4410 5060);
DISPLAY 1.021277 (-4410 5060);
WIRE 16 -1 (-4500 6600)(-2900 6600);
FORCEPROP 2 LAST SIG_NAME FPGA_OUT_SMA4_LED_GREEN_N
J 0
(-4460 6610);
DISPLAY 1.021277 (-4460 6610);
WIRE 16 -1 (-9600 4000)(-9300 4000);
WIRE 16 -1 (-9600 3850)(-9600 4000);
WIRE 16 -1 (-2900 6450)(-4500 6450);
FORCEPROP 2 LAST SIG_NAME SMA4_LED_RED_N
J 0
(-4460 6460);
DISPLAY 1.021277 (-4460 6460);
WIRE 16 -1 (-4500 7700)(-2900 7700);
FORCEPROP 2 LAST SIG_NAME SMA3_LED_BLUE_N
J 0
(-4460 7710);
DISPLAY 1.021277 (-4460 7710);
WIRE 16 -1 (-4500 10600)(-2900 10600);
FORCEPROP 2 LAST SIG_NAME FPGA_OUT_SMA1_LED_BLUE_N
J 0
(-4460 10610);
DISPLAY 1.021277 (-4460 10610);
WIRE 16 -1 (-4500 11350)(-2900 11350);
FORCEPROP 2 LAST SIG_NAME SMA1_LED_GREEN_N
J 0
(-4460 11360);
DISPLAY 1.021277 (-4460 11360);
WIRE 16 -1 (-4450 4750)(-2850 4750);
FORCEPROP 2 LAST SIG_NAME FPGA_OUT_GPS_LED_RED_N
J 0
(-4410 4760);
DISPLAY 1.021277 (-4410 4760);
WIRE 16 -1 (-4500 8300)(-2900 8300);
FORCEPROP 2 LAST SIG_NAME SMA3_LED_GREEN_N
J 0
(-4460 8310);
DISPLAY 1.021277 (-4460 8310);
WIRE 16 -1 (-4500 9250)(-2900 9250);
FORCEPROP 2 LAST SIG_NAME SMA2_LED_BLUE_N
J 0
(-4460 9260);
DISPLAY 1.021277 (-4460 9260);
WIRE 16 -1 (-4500 10750)(-2900 10750);
FORCEPROP 2 LAST SIG_NAME SMA1_LED_BLUE_N
J 0
(-4460 10760);
DISPLAY 1.021277 (-4460 10760);
WIRE 16 -1 (-4500 10900)(-2900 10900);
FORCEPROP 2 LAST SIG_NAME FPGA_OUT_SMA1_LED_RED_N
J 0
(-4460 10910);
DISPLAY 1.021277 (-4460 10910);
WIRE 16 -1 (-4500 11200)(-2900 11200);
FORCEPROP 2 LAST SIG_NAME FPGA_OUT_SMA1_LED_GREEN_N
J 0
(-4460 11210);
DISPLAY 1.021277 (-4460 11210);
WIRE 16 -1 (-2850 4900)(-4450 4900);
FORCEPROP 2 LAST SIG_NAME GPS_SMA_LED_RED_N
J 0
(-4410 4910);
DISPLAY 1.021277 (-4410 4910);
WIRE 16 -1 (-2100 10750)(-2100 10600);
WIRE 16 -1 (-2650 10750)(-2100 10750);
WIRE 16 -1 (-2100 10750)(-2000 10750);
WIRE 16 -1 (-2100 10600)(-2650 10600);
WIRE 16 -1 (-2100 8000)(-2100 7850);
WIRE 16 -1 (-2000 8000)(-2100 8000);
WIRE 16 -1 (-2100 8000)(-2650 8000);
WIRE 16 -1 (-2100 7850)(-2650 7850);
WIRE 16 -1 (-2100 8300)(-2100 8150);
WIRE 16 -1 (-2100 8300)(-2000 8300);
WIRE 16 -1 (-2650 8300)(-2100 8300);
WIRE 16 -1 (-2100 8150)(-2650 8150);
WIRE 16 -1 (-2100 7700)(-2100 7550);
WIRE 16 -1 (-2650 7700)(-2100 7700);
WIRE 16 -1 (-2100 7700)(-2000 7700);
WIRE 16 -1 (-2100 7550)(-2650 7550);
WIRE 16 -1 (-2100 6450)(-2100 6300);
WIRE 16 -1 (-2000 6450)(-2100 6450);
WIRE 16 -1 (-2100 6450)(-2650 6450);
WIRE 16 -1 (-2100 6300)(-2650 6300);
WIRE 16 -1 (-2100 6750)(-2100 6600);
WIRE 16 -1 (-2650 6750)(-2100 6750);
WIRE 16 -1 (-2100 6750)(-2000 6750);
WIRE 16 -1 (-2100 6600)(-2650 6600);
WIRE 16 -1 (-2100 6150)(-2100 6000);
WIRE 16 -1 (-2100 6150)(-2000 6150);
WIRE 16 -1 (-2650 6150)(-2100 6150);
WIRE 16 -1 (-2100 6000)(-2650 6000);
WIRE 16 -1 (-2100 5200)(-2100 5050);
WIRE 16 -1 (-2100 5200)(-2000 5200);
WIRE 16 -1 (-2600 5200)(-2100 5200);
WIRE 16 -1 (-2100 5050)(-2600 5050);
WIRE 16 -1 (-2100 4600)(-2100 4450);
WIRE 16 -1 (-2600 4600)(-2100 4600);
WIRE 16 -1 (-2100 4600)(-2000 4600);
WIRE 16 -1 (-2100 4450)(-2600 4450);
WIRE 16 -1 (-4450 4450)(-2850 4450);
FORCEPROP 2 LAST SIG_NAME FPGA_OUT_GPS_LED_BLUE_N
J 0
(-4410 4460);
DISPLAY 1.021277 (-4410 4460);
WIRE 16 -1 (-4450 5200)(-2850 5200);
FORCEPROP 2 LAST SIG_NAME GPS_SMA_LED_GREEN_N
J 0
(-4410 5210);
DISPLAY 1.021277 (-4410 5210);
WIRE 16 -1 (-2100 4900)(-2100 4750);
WIRE 16 -1 (-2000 4900)(-2100 4900);
WIRE 16 -1 (-2100 4900)(-2600 4900);
WIRE 16 -1 (-2100 4750)(-2600 4750);
WIRE 16 -1 (-2100 11050)(-2100 10900);
WIRE 16 -1 (-2000 11050)(-2100 11050);
WIRE 16 -1 (-2100 11050)(-2650 11050);
WIRE 16 -1 (-2100 10900)(-2650 10900);
WIRE 16 -1 (-2100 11350)(-2100 11200);
WIRE 16 -1 (-2100 11350)(-2000 11350);
WIRE 16 -1 (-2650 11350)(-2100 11350);
WIRE 16 -1 (-2100 11200)(-2650 11200);
WIRE 16 -1 (-4500 6150)(-2900 6150);
FORCEPROP 2 LAST SIG_NAME SMA4_LED_BLUE_N
J 0
(-4460 6160);
DISPLAY 1.021277 (-4460 6160);
WIRE 16 -1 (-2900 8000)(-4500 8000);
FORCEPROP 2 LAST SIG_NAME SMA3_LED_RED_N
J 0
(-4460 8010);
DISPLAY 1.021277 (-4460 8010);
WIRE 16 -1 (-2100 9850)(-2100 9700);
WIRE 16 -1 (-2650 9850)(-2100 9850);
WIRE 16 -1 (-2100 9850)(-2000 9850);
WIRE 16 -1 (-2100 9700)(-2650 9700);
WIRE 16 -1 (-2900 11050)(-4500 11050);
FORCEPROP 2 LAST SIG_NAME SMA1_LED_RED_N
J 0
(-4460 11060);
DISPLAY 1.021277 (-4460 11060);
WIRE 16 -1 (-2100 9550)(-2100 9400);
WIRE 16 -1 (-2000 9550)(-2100 9550);
WIRE 16 -1 (-2100 9550)(-2650 9550);
WIRE 16 -1 (-2100 9400)(-2650 9400);
WIRE 16 -1 (-4500 9100)(-2900 9100);
FORCEPROP 2 LAST SIG_NAME FPGA_OUT_SMA2_LED_BLUE_N
J 0
(-4460 9110);
DISPLAY 1.021277 (-4460 9110);
WIRE 16 -1 (-6750 4500)(-8350 4500);
FORCEPROP 2 LAST SIG_NAME SMA4_LED_BLUE_N
J 0
(-7710 4510);
DISPLAY 1.021277 (-7710 4510);
WIRE 16 -1 (-8350 4600)(-6750 4600);
FORCEPROP 2 LAST SIG_NAME SMA4_LED_RED_N
J 0
(-7710 4610);
DISPLAY 1.021277 (-7710 4610);
WIRE 16 -1 (-4500 7550)(-2900 7550);
FORCEPROP 2 LAST SIG_NAME FPGA_OUT_SMA3_LED_BLUE_N
J 0
(-4460 7560);
DISPLAY 1.021277 (-4460 7560);
WIRE 16 -1 (-4500 8150)(-2900 8150);
FORCEPROP 2 LAST SIG_NAME FPGA_OUT_SMA3_LED_GREEN_N
J 0
(-4460 8160);
DISPLAY 1.021277 (-4460 8160);
WIRE 16 -1 (-2100 9250)(-2100 9100);
WIRE 16 -1 (-2100 9250)(-2000 9250);
WIRE 16 -1 (-2650 9250)(-2100 9250);
WIRE 16 -1 (-2100 9100)(-2650 9100);
WIRE 16 -1 (-2900 9550)(-4500 9550);
FORCEPROP 2 LAST SIG_NAME SMA2_LED_RED_N
J 0
(-4460 9560);
DISPLAY 1.021277 (-4460 9560);
WIRE 16 -1 (-9450 8850)(-8750 8850);
WIRE 16 -1 (-10350 8850)(-9700 8850);
WIRE 16 -1 (-10750 12400)(-12750 12400);
FORCEPROP 2 LAST SIG_NAME LED_DATOUT3
J 0
(-12660 12410);
DISPLAY 1.021277 (-12660 12410);
WIRE 16 -1 (-11000 10200)(-10250 10200);
WIRE 16 -1 (-10350 9200)(-9350 9200);
WIRE 16 -1 (-10350 8100)(-9750 8100);
WIRE 16 -1 (-10350 7400)(-9350 7400);
WIRE 16 -1 (-10350 7050)(-9350 7050);
WIRE 16 -1 (-4500 9400)(-2900 9400);
FORCEPROP 2 LAST SIG_NAME FPGA_OUT_SMA2_LED_RED_N
J 0
(-4460 9410);
DISPLAY 1.021277 (-4460 9410);
WIRE 16 -1 (-10250 11350)(-9000 11350);
WIRE 16 -1 (-10350 7750)(-9350 7750);
WIRE 16 -1 (-9500 8100)(-8850 8100);
WIRE 16 -1 (-10350 8500)(-9250 8500);
WIRE 16 -1 (-10250 10650)(-9000 10650);
WIRE 16 -1 (-10750 10650)(-12750 10650);
FORCEPROP 2 LAST SIG_NAME FPGA_USR_LED0
J 0
(-12660 10660);
DISPLAY 1.021277 (-12660 10660);
WIRE 16 -1 (-10750 10950)(-12750 10950);
FORCEPROP 2 LAST SIG_NAME FPGA_USR_LED1
J 0
(-12660 10960);
DISPLAY 1.021277 (-12660 10960);
WIRE 16 -1 (-10750 12050)(-12750 12050);
FORCEPROP 2 LAST SIG_NAME LED_DATOUT2
J 0
(-12660 12060);
DISPLAY 1.021277 (-12660 12060);
WIRE 16 -1 (-8350 10200)(-10000 10200);
FORCEPROP 2 LAST SIG_NAME FPGA_DONE
J 0
(-9110 10210);
DISPLAY 1.021277 (-9110 10210);
WIRE 16 -1 (-10250 10950)(-9000 10950);
WIRE 16 -1 (-10250 11700)(-9000 11700);
WIRE 16 -1 (-10250 12050)(-9000 12050);
WIRE 16 -1 (-10250 12400)(-9000 12400);
DOT 1 (-11400 5300);
DOT 1 (-5550 6650);
DOT 1 (-9700 4800);
DOT 1 (-9700 6150);
DOT 1 (-10150 5650);
DOT 1 (-10550 6150);
DOT 1 (-10150 6150);
DOT 1 (-11000 5200);
DOT 1 (-10750 5100);
DOT 1 (-7700 10950);
DOT 1 (-8150 3600);
DOT 1 (-8150 3500);
DOT 1 (-8150 3200);
DOT 1 (-450 11050);
DOT 1 (-450 9550);
DOT 1 (-450 8000);
DOT 1 (-450 6450);
DOT 1 (-2100 9550);
DOT 1 (-2100 9250);
DOT 1 (-2100 8000);
DOT 1 (-2100 7700);
DOT 1 (-2100 6750);
DOT 1 (-2100 5200);
DOT 1 (-2100 4900);
DOT 1 (-2100 4600);
DOT 1 (-10050 3450);
DOT 1 (-8150 3400);
DOT 1 (-2100 11350);
DOT 1 (-2100 11050);
DOT 1 (-2100 10750);
DOT 1 (-2100 9850);
DOT 1 (-2100 8300);
DOT 1 (-2100 6150);
DOT 1 (-2100 6450);
DOT 1 (-9950 4800);
DOT 1 (-5550 9850);
DOT 1 (-7700 12400);
DOT 1 (-7700 12050);
DOT 1 (-7700 11700);
DOT 1 (-7700 11350);
DOT 1 (-12250 8850);
DOT 1 (-12250 8500);
DOT 1 (-12250 7750);
DOT 1 (-12250 8100);
DOT 1 (-12250 7400);
DOT 1 (-12250 7050);
DOT 1 (-9750 4800);
DOT 1 (-11000 6150);
DOT 1 (-11400 6150);
DOT 1 (-10850 5000);
FORCENOTE
ADDR: 011 0100 , 0X34
(-12400 3850) 0;
DISPLAY LEFT (-12400 3850);
DISPLAY 2.000000 (-12400 3850);
FORCENOTE
I2C<>RGB_LED_DRIVER
(-9800 6350) 0;
DISPLAY LEFT (-9800 6350);
DISPLAY 2.468085 (-9800 6350);
FORCENOTE
R_ISET=4K7,I_OUT.MAX EACH LED = 16.2MA
(-12650 3600) 0;
DISPLAY LEFT (-12650 3600);
DISPLAY 1.276596 (-12650 3600);
FORCENOTE
GREEN_LED
(-10600 11500) 0;
DISPLAY LEFT (-10600 11500);
DISPLAY 1.021277 (-10600 11500);
FORCENOTE
GREEN_LED
(-10600 10800) 0;
DISPLAY LEFT (-10600 10800);
DISPLAY 1.021277 (-10600 10800);
FORCENOTE
GREEN_LED
(-10600 11100) 0;
DISPLAY LEFT (-10600 11100);
DISPLAY 1.021277 (-10600 11100);
FORCENOTE
FPGA_DONE_LED
(-10650 10350) 0;
DISPLAY LEFT (-10650 10350);
DISPLAY 1.978723 (-10650 10350);
FORCENOTE
GREEN_LED
(-10700 8650) 0;
DISPLAY LEFT (-10700 8650);
DISPLAY 1.021277 (-10700 8650);
FORCENOTE
RGB_LED_STATUS
(-3300 12350) 0;
DISPLAY LEFT (-3300 12350);
DISPLAY 3.085106 (-3300 12350);
FORCENOTE
GREEN_LED
(-10700 9350) 0;
DISPLAY LEFT (-10700 9350);
DISPLAY 1.021277 (-10700 9350);
FORCENOTE
GREEN_LED
(-10700 9000) 0;
DISPLAY LEFT (-10700 9000);
DISPLAY 1.021277 (-10700 9000);
FORCENOTE
GREEN_LED
(-11350 10350) 0;
DISPLAY LEFT (-11350 10350);
DISPLAY 1.021277 (-11350 10350);
FORCENOTE
GREEN_LED
(-10600 11850) 0;
DISPLAY LEFT (-10600 11850);
DISPLAY 1.021277 (-10600 11850);
FORCENOTE
GREEN_LED
(-10700 8250) 0;
DISPLAY LEFT (-10700 8250);
DISPLAY 1.021277 (-10700 8250);
FORCENOTE
GREEN_LED
(-10700 7900) 0;
DISPLAY LEFT (-10700 7900);
DISPLAY 1.021277 (-10700 7900);
FORCENOTE
GREEN_LED
(-10700 7550) 0;
DISPLAY LEFT (-10700 7550);
DISPLAY 1.021277 (-10700 7550);
FORCENOTE
GREEN_LED
(-10700 7200) 0;
DISPLAY LEFT (-10700 7200);
DISPLAY 1.021277 (-10700 7200);
FORCENOTE
GREEN_LED
(-10600 12550) 0;
DISPLAY LEFT (-10600 12550);
DISPLAY 1.021277 (-10600 12550);
FORCENOTE
GREEN_LED
(-10600 12200) 0;
DISPLAY LEFT (-10600 12200);
DISPLAY 1.021277 (-10600 12200);
FORCENOTE
USR_LED_STATUS
(-11050 12800) 0;
DISPLAY LEFT (-11050 12800);
DISPLAY 2.468085 (-11050 12800);
FORCENOTE
PWR_LED_STATUS
(-10900 9550) 0;
DISPLAY LEFT (-10900 9550);
DISPLAY 2.468085 (-10900 9550);
QUIT
